G04 ================== begin FILE IDENTIFICATION RECORD ==================*
G04 Layout Name:  14545-sa.brd*
G04 Film Name:    DRILL*
G04 File Format:  Gerber RS274X*
G04 File Origin:  Cadence Allegro 16.5-S056*
G04 Origin Date:  Fri Aug 01 17:58:18 2014*
G04 *
G04 Layer:  MANUFACTURING/NCLEGEND-1-8*
G04 Layer:  MANUFACTURING/DRILL SIZE*
G04 Layer:  DRAWING FORMAT/LAYER_PCB_STORY*
G04 Layer:  DRAWING FORMAT/LAYER_DRILL*
G04 Layer:  BOARD GEOMETRY/PANEL_OUTLINE*
G04 *
G04 Offset:    (0.00 0.00)*
G04 Mirror:    No*
G04 Mode:      Positive*
G04 Rotation:  0*
G04 FullContactRelief:  No*
G04 UndefLineWidth:     6.00*
G04 ================== end FILE IDENTIFICATION RECORD ====================*
%FSLAX35Y35*MOIN*%
%IR0*IPPOS*OFA0.00000B0.00000*MIA0B0*SFA1.00000B1.00000*%
%AMMACRO13*
1,1,.006,.006,0.0*
20,1,.006,.006,0.0,-.006,0.0,0.0*
1,1,.006,-.006,0.0*
1,1,.006,0.0,.006*
20,1,.006,0.0,.006,0.0,-.006,0.0*
1,1,.006,0.0,-.006*
1,1,.006,.003,0.0*
20,1,.006,.003,0.0,.003,.006,0.0*
1,1,.006,.003,.006*
20,1,.006,.003,.006,.0018,.0048,0.0*
1,1,.006,.0018,.0048*
1,1,.006,.0018,0.0*
20,1,.006,.0018,0.0,.0042,0.0,0.0*
1,1,.006,.0042,0.0*
%
%ADD13MACRO13*%
%AMMACRO11*
1,1,.006,.008,.008*
20,1,.006,.008,.008,.008,-.008,0.0*
1,1,.006,.008,-.008*
20,1,.006,.008,-.008,-.008,-.008,0.0*
1,1,.006,-.008,-.008*
20,1,.006,-.008,-.008,-.008,.008,0.0*
1,1,.006,-.008,.008*
20,1,.006,-.008,.008,.008,.008,0.0*
1,1,.006,.008,.008*
1,1,.006,-.00253,.00267*
20,1,.006,-.00253,.00267,-.00173,.00347,0.0*
1,1,.006,-.00173,.00347*
20,1,.006,-.00173,.00347,-.0008,.00387,0.0*
1,1,.006,-.0008,.00387*
20,1,.006,-.0008,.00387,.00027,.004,0.0*
1,1,.006,.00027,.004*
20,1,.006,.00027,.004,.0016,.00373,0.0*
1,1,.006,.0016,.00373*
20,1,.006,.0016,.00373,.00253,.00307,0.0*
1,1,.006,.00253,.00307*
20,1,.006,.00253,.00307,.0028,.00227,0.0*
1,1,.006,.0028,.00227*
20,1,.006,.0028,.00227,.00267,.00147,0.0*
1,1,.006,.00267,.00147*
20,1,.006,.00267,.00147,.00213,.0008,0.0*
1,1,.006,.00213,.0008*
20,1,.006,.00213,.0008,-.00053,-.00053,0.0*
1,1,.006,-.00053,-.00053*
20,1,.006,-.00053,-.00053,-.00173,-.00147,0.0*
1,1,.006,-.00173,-.00147*
20,1,.006,-.00173,-.00147,-.00253,-.0028,0.0*
1,1,.006,-.00253,-.0028*
20,1,.006,-.00253,-.0028,-.0028,-.004,0.0*
1,1,.006,-.0028,-.004*
20,1,.006,-.0028,-.004,.0028,-.004,0.0*
1,1,.006,.0028,-.004*
%
%ADD11MACRO11*%
%AMMACRO16*
1,1,.006,.015119,-.0365*
20,1,.006,.015119,-.0365,-.015119,-.0365,0.0*
1,1,.006,-.015119,-.0365*
20,1,.006,-.015119,-.0365,-.0365,-.015119,0.0*
1,1,.006,-.0365,-.015119*
20,1,.006,-.0365,-.015119,-.0365,.015119,0.0*
1,1,.006,-.0365,.015119*
20,1,.006,-.0365,.015119,-.015119,.0365,0.0*
1,1,.006,-.015119,.0365*
20,1,.006,-.015119,.0365,.015119,.0365,0.0*
1,1,.006,.015119,.0365*
20,1,.006,.015119,.0365,.0365,.015119,0.0*
1,1,.006,.0365,.015119*
20,1,.006,.0365,.015119,.0365,-.015119,0.0*
1,1,.006,.0365,-.015119*
20,1,.006,.0365,-.015119,.015119,-.0365,0.0*
1,1,.006,.015119,-.0365*
1,1,.006,-.01338,-.01278*
20,1,.006,-.01338,-.01278,-.00973,-.01582,0.0*
1,1,.006,-.00973,-.01582*
20,1,.006,-.00973,-.01582,-.00548,-.01764,0.0*
1,1,.006,-.00548,-.01764*
20,1,.006,-.00548,-.01764,0.0,-.01825,0.0*
1,1,.006,0.0,-.01825*
20,1,.006,0.0,-.01825,.00548,-.01703,0.0*
1,1,.006,.00548,-.01703*
20,1,.006,.00548,-.01703,.00973,-.0146,0.0*
1,1,.006,.00973,-.0146*
20,1,.006,.00973,-.0146,.01278,-.01034,0.0*
1,1,.006,.01278,-.01034*
20,1,.006,.01278,-.01034,.01338,-.00548,0.0*
1,1,.006,.01338,-.00548*
20,1,.006,.01338,-.00548,.01217,-.00061,0.0*
1,1,.006,.01217,-.00061*
20,1,.006,.01217,-.00061,.00912,.00243,0.0*
1,1,.006,.00912,.00243*
20,1,.006,.00912,.00243,.00487,.00487,0.0*
1,1,.006,.00487,.00487*
20,1,.006,.00487,.00487,.00061,.00547,0.0*
1,1,.006,.00061,.00547*
20,1,.006,.00061,.00547,-.00365,.00487,0.0*
1,1,.006,-.00365,.00487*
20,1,.006,-.00365,.00487,-.00912,.00243,0.0*
1,1,.006,-.00912,.00243*
20,1,.006,-.00912,.00243,-.0073,.01825,0.0*
1,1,.006,-.0073,.01825*
20,1,.006,-.0073,.01825,.00912,.01825,0.0*
1,1,.006,.00912,.01825*
%
%ADD16MACRO16*%
%AMMACRO10*
1,1,.006,.043,0.0*
20,1,.006,.043,0.0,0.0,-.043,0.0*
1,1,.006,0.0,-.043*
20,1,.006,0.0,-.043,-.043,0.0,0.0*
1,1,.006,-.043,0.0*
20,1,.006,-.043,0.0,0.0,.043,0.0*
1,1,.006,0.0,.043*
20,1,.006,0.0,.043,.043,0.0,0.0*
1,1,.006,.043,0.0*
1,1,.006,-.01362,-.00358*
20,1,.006,-.01362,-.00358,-.0086,.00143,0.0*
1,1,.006,-.0086,.00143*
20,1,.006,-.0086,.00143,-.0043,.0043,0.0*
1,1,.006,-.0043,.0043*
20,1,.006,-.0043,.0043,.00143,.00573,0.0*
1,1,.006,.00143,.00573*
20,1,.006,.00143,.00573,.00645,.0043,0.0*
1,1,.006,.00645,.0043*
20,1,.006,.00645,.0043,.01003,.00143,0.0*
1,1,.006,.01003,.00143*
20,1,.006,.01003,.00143,.0129,-.00287,0.0*
1,1,.006,.0129,-.00287*
20,1,.006,.0129,-.00287,.01362,-.00788,0.0*
1,1,.006,.01362,-.00788*
20,1,.006,.01362,-.00788,.0129,-.01218,0.0*
1,1,.006,.0129,-.01218*
20,1,.006,.0129,-.01218,.01003,-.01648,0.0*
1,1,.006,.01003,-.01648*
20,1,.006,.01003,-.01648,.00573,-.02007,0.0*
1,1,.006,.00573,-.02007*
20,1,.006,.00573,-.02007,.00072,-.0215,0.0*
1,1,.006,.00072,-.0215*
20,1,.006,.00072,-.0215,-.00502,-.02007,0.0*
1,1,.006,-.00502,-.02007*
20,1,.006,-.00502,-.02007,-.01003,-.01577,0.0*
1,1,.006,-.01003,-.01577*
20,1,.006,-.01003,-.01577,-.0129,-.00932,0.0*
1,1,.006,-.0129,-.00932*
20,1,.006,-.0129,-.00932,-.01362,-.00215,0.0*
1,1,.006,-.01362,-.00215*
20,1,.006,-.01362,-.00215,-.01218,.00717,0.0*
1,1,.006,-.01218,.00717*
20,1,.006,-.01218,.00717,-.01003,.01218,0.0*
1,1,.006,-.01003,.01218*
20,1,.006,-.01003,.01218,-.00645,.0172,0.0*
1,1,.006,-.00645,.0172*
20,1,.006,-.00645,.0172,-.00143,.02078,0.0*
1,1,.006,-.00143,.02078*
20,1,.006,-.00143,.02078,.00358,.0215,0.0*
1,1,.006,.00358,.0215*
20,1,.006,.00358,.0215,.0086,.02007,0.0*
1,1,.006,.0086,.02007*
20,1,.006,.0086,.02007,.01218,.01648,0.0*
1,1,.006,.01218,.01648*
%
%ADD10MACRO10*%
%AMMACRO14*
1,1,.006,.07,0.0*
20,1,.006,.07,0.0,.035,.060622,0.0*
1,1,.006,.035,.060622*
20,1,.006,.035,.060622,-.035,.060622,0.0*
1,1,.006,-.035,.060622*
20,1,.006,-.035,.060622,-.07,0.0,0.0*
1,1,.006,-.07,0.0*
20,1,.006,-.07,0.0,-.035,-.060622,0.0*
1,1,.006,-.035,-.060622*
20,1,.006,-.035,-.060622,.035,-.060622,0.0*
1,1,.006,.035,-.060622*
20,1,.006,.035,-.060622,.07,0.0,0.0*
1,1,.006,.07,0.0*
1,1,.006,-.02567,-.021*
20,1,.006,-.02567,-.021,-.01867,-.02917,0.0*
1,1,.006,-.01867,-.02917*
20,1,.006,-.01867,-.02917,-.00933,-.03383,0.0*
1,1,.006,-.00933,-.03383*
20,1,.006,-.00933,-.03383,.00117,-.035,0.0*
1,1,.006,.00117,-.035*
20,1,.006,.00117,-.035,.0105,-.03383,0.0*
1,1,.006,.0105,-.03383*
20,1,.006,.0105,-.03383,.01983,-.028,0.0*
1,1,.006,.01983,-.028*
20,1,.006,.01983,-.028,.02567,-.021,0.0*
1,1,.006,.02567,-.021*
20,1,.006,.02567,-.021,.02683,-.014,0.0*
1,1,.006,.02683,-.014*
20,1,.006,.02683,-.014,.0245,-.00584,0.0*
1,1,.006,.0245,-.00584*
20,1,.006,.0245,-.00584,.01633,0.0,0.0*
1,1,.006,.01633,0.0*
20,1,.006,.01633,0.0,.00817,.00233,0.0*
1,1,.006,.00817,.00233*
20,1,.006,.00817,.00233,-.00233,.00233,0.0*
1,1,.006,-.00233,.00233*
1,1,.006,.00817,.00233*
20,1,.006,.00817,.00233,.01517,.00583,0.0*
1,1,.006,.01517,.00583*
20,1,.006,.01517,.00583,.021,.01167,0.0*
1,1,.006,.021,.01167*
20,1,.006,.021,.01167,.02333,.01867,0.0*
1,1,.006,.02333,.01867*
20,1,.006,.02333,.01867,.021,.02567,0.0*
1,1,.006,.021,.02567*
20,1,.006,.021,.02567,.01517,.0315,0.0*
1,1,.006,.01517,.0315*
20,1,.006,.01517,.0315,.00467,.035,0.0*
1,1,.006,.00467,.035*
20,1,.006,.00467,.035,-.00583,.03383,0.0*
1,1,.006,-.00583,.03383*
20,1,.006,-.00583,.03383,-.01633,.02917,0.0*
1,1,.006,-.01633,.02917*
%
%ADD14MACRO14*%
%AMMACRO15*
1,1,.006,-.0215,.016*
20,1,.006,-.0215,.016,.0215,.016,0.0*
1,1,.006,.0215,.016*
20,1,.006,.0215,.016,.024278,.015757,0.0*
1,1,.006,.024278,.015757*
20,1,.006,.024278,.015757,.026972,.015035,0.0*
1,1,.006,.026972,.015035*
20,1,.006,.026972,.015035,.0295,.013856,0.0*
1,1,.006,.0295,.013856*
20,1,.006,.0295,.013856,.031785,.012257,0.0*
1,1,.006,.031785,.012257*
20,1,.006,.031785,.012257,.033757,.010285,0.0*
1,1,.006,.033757,.010285*
20,1,.006,.033757,.010285,.035356,.008,0.0*
1,1,.006,.035356,.008*
20,1,.006,.035356,.008,.036535,.005472,0.0*
1,1,.006,.036535,.005472*
20,1,.006,.036535,.005472,.037257,.002778,0.0*
1,1,.006,.037257,.002778*
20,1,.006,.037257,.002778,.0375,0.0,0.0*
1,1,.006,.0375,0.0*
20,1,.006,.0375,0.0,.037257,-.002778,0.0*
1,1,.006,.037257,-.002778*
20,1,.006,.037257,-.002778,.036535,-.005472,0.0*
1,1,.006,.036535,-.005472*
20,1,.006,.036535,-.005472,.035356,-.008,0.0*
1,1,.006,.035356,-.008*
20,1,.006,.035356,-.008,.033757,-.010285,0.0*
1,1,.006,.033757,-.010285*
20,1,.006,.033757,-.010285,.031785,-.012257,0.0*
1,1,.006,.031785,-.012257*
20,1,.006,.031785,-.012257,.0295,-.013856,0.0*
1,1,.006,.0295,-.013856*
20,1,.006,.0295,-.013856,.026972,-.015035,0.0*
1,1,.006,.026972,-.015035*
20,1,.006,.026972,-.015035,.024278,-.015757,0.0*
1,1,.006,.024278,-.015757*
20,1,.006,.024278,-.015757,.0215,-.016,0.0*
1,1,.006,.0215,-.016*
20,1,.006,.0215,-.016,-.0215,-.016,0.0*
1,1,.006,-.0215,-.016*
20,1,.006,-.0215,-.016,-.024278,-.015757,0.0*
1,1,.006,-.024278,-.015757*
20,1,.006,-.024278,-.015757,-.026972,-.015035,0.0*
1,1,.006,-.026972,-.015035*
20,1,.006,-.026972,-.015035,-.0295,-.013856,0.0*
1,1,.006,-.0295,-.013856*
20,1,.006,-.0295,-.013856,-.031785,-.012257,0.0*
1,1,.006,-.031785,-.012257*
20,1,.006,-.031785,-.012257,-.033757,-.010285,0.0*
1,1,.006,-.033757,-.010285*
20,1,.006,-.033757,-.010285,-.035356,-.008,0.0*
1,1,.006,-.035356,-.008*
20,1,.006,-.035356,-.008,-.036535,-.005472,0.0*
1,1,.006,-.036535,-.005472*
20,1,.006,-.036535,-.005472,-.037257,-.002778,0.0*
1,1,.006,-.037257,-.002778*
20,1,.006,-.037257,-.002778,-.0375,0.0,0.0*
1,1,.006,-.0375,0.0*
20,1,.006,-.0375,0.0,-.037257,.002778,0.0*
1,1,.006,-.037257,.002778*
20,1,.006,-.037257,.002778,-.036535,.005472,0.0*
1,1,.006,-.036535,.005472*
20,1,.006,-.036535,.005472,-.035356,.008,0.0*
1,1,.006,-.035356,.008*
20,1,.006,-.035356,.008,-.033757,.010285,0.0*
1,1,.006,-.033757,.010285*
20,1,.006,-.033757,.010285,-.031785,.012257,0.0*
1,1,.006,-.031785,.012257*
20,1,.006,-.031785,.012257,-.0295,.013856,0.0*
1,1,.006,-.0295,.013856*
20,1,.006,-.0295,.013856,-.026972,.015035,0.0*
1,1,.006,-.026972,.015035*
20,1,.006,-.026972,.015035,-.024278,.015757,0.0*
1,1,.006,-.024278,.015757*
20,1,.006,-.024278,.015757,-.0215,.016,0.0*
1,1,.006,-.0215,.016*
1,1,.006,-.00453,-.00613*
20,1,.006,-.00453,-.00613,-.00267,-.00747,0.0*
1,1,.006,-.00267,-.00747*
20,1,.006,-.00267,-.00747,-.00053,-.008,0.0*
1,1,.006,-.00053,-.008*
20,1,.006,-.00053,-.008,.0016,-.00747,0.0*
1,1,.006,.0016,-.00747*
20,1,.006,.0016,-.00747,.00347,-.00587,0.0*
1,1,.006,.00347,-.00587*
20,1,.006,.00347,-.00587,.0048,-.00347,0.0*
1,1,.006,.0048,-.00347*
20,1,.006,.0048,-.00347,.00533,-.00107,0.0*
1,1,.006,.00533,-.00107*
20,1,.006,.00533,-.00107,.00533,.00187,0.0*
1,1,.006,.00533,.00187*
20,1,.006,.00533,.00187,.0048,.00427,0.0*
1,1,.006,.0048,.00427*
20,1,.006,.0048,.00427,.00347,.0064,0.0*
1,1,.006,.00347,.0064*
20,1,.006,.00347,.0064,.00187,.00747,0.0*
1,1,.006,.00187,.00747*
20,1,.006,.00187,.00747,0.0,.008,0.0*
1,1,.006,0.0,.008*
20,1,.006,0.0,.008,-.00213,.00747,0.0*
1,1,.006,-.00213,.00747*
20,1,.006,-.00213,.00747,-.00373,.0064,0.0*
1,1,.006,-.00373,.0064*
20,1,.006,-.00373,.0064,-.0048,.0048,0.0*
1,1,.006,-.0048,.0048*
20,1,.006,-.0048,.0048,-.00533,.00267,0.0*
1,1,.006,-.00533,.00267*
20,1,.006,-.00533,.00267,-.0048,.0008,0.0*
1,1,.006,-.0048,.0008*
20,1,.006,-.0048,.0008,-.00347,-.00107,0.0*
1,1,.006,-.00347,-.00107*
20,1,.006,-.00347,-.00107,-.00187,-.00213,0.0*
1,1,.006,-.00187,-.00213*
20,1,.006,-.00187,-.00213,0.0,-.0024,0.0*
1,1,.006,0.0,-.0024*
20,1,.006,0.0,-.0024,.00213,-.00187,0.0*
1,1,.006,.00213,-.00187*
20,1,.006,.00213,-.00187,.00373,-.00053,0.0*
1,1,.006,.00373,-.00053*
20,1,.006,.00373,-.00053,.00533,.00187,0.0*
1,1,.006,.00533,.00187*
%
%ADD15MACRO15*%
%AMMACRO18*
1,1,.006,-.01825,.05475*
20,1,.006,-.01825,.05475,.01825,.05475,0.0*
1,1,.006,.01825,.05475*
20,1,.006,.01825,.05475,.027757,.053918,0.0*
1,1,.006,.027757,.053918*
20,1,.006,.027757,.053918,.036976,.051448,0.0*
1,1,.006,.036976,.051448*
20,1,.006,.036976,.051448,.045625,.047415,0.0*
1,1,.006,.045625,.047415*
20,1,.006,.045625,.047415,.053443,.041941,0.0*
1,1,.006,.053443,.041941*
20,1,.006,.053443,.041941,.060191,.035193,0.0*
1,1,.006,.060191,.035193*
20,1,.006,.060191,.035193,.065665,.027375,0.0*
1,1,.006,.065665,.027375*
20,1,.006,.065665,.027375,.069698,.018726,0.0*
1,1,.006,.069698,.018726*
20,1,.006,.069698,.018726,.072168,.009507,0.0*
1,1,.006,.072168,.009507*
20,1,.006,.072168,.009507,.073,0.0,0.0*
1,1,.006,.073,0.0*
20,1,.006,.073,0.0,.072168,-.009507,0.0*
1,1,.006,.072168,-.009507*
20,1,.006,.072168,-.009507,.069698,-.018726,0.0*
1,1,.006,.069698,-.018726*
20,1,.006,.069698,-.018726,.065665,-.027375,0.0*
1,1,.006,.065665,-.027375*
20,1,.006,.065665,-.027375,.060191,-.035193,0.0*
1,1,.006,.060191,-.035193*
20,1,.006,.060191,-.035193,.053443,-.041941,0.0*
1,1,.006,.053443,-.041941*
20,1,.006,.053443,-.041941,.045625,-.047415,0.0*
1,1,.006,.045625,-.047415*
20,1,.006,.045625,-.047415,.036976,-.051448,0.0*
1,1,.006,.036976,-.051448*
20,1,.006,.036976,-.051448,.027757,-.053918,0.0*
1,1,.006,.027757,-.053918*
20,1,.006,.027757,-.053918,.01825,-.05475,0.0*
1,1,.006,.01825,-.05475*
20,1,.006,.01825,-.05475,-.01825,-.05475,0.0*
1,1,.006,-.01825,-.05475*
20,1,.006,-.01825,-.05475,-.027757,-.053918,0.0*
1,1,.006,-.027757,-.053918*
20,1,.006,-.027757,-.053918,-.036976,-.051448,0.0*
1,1,.006,-.036976,-.051448*
20,1,.006,-.036976,-.051448,-.045625,-.047415,0.0*
1,1,.006,-.045625,-.047415*
20,1,.006,-.045625,-.047415,-.053443,-.041941,0.0*
1,1,.006,-.053443,-.041941*
20,1,.006,-.053443,-.041941,-.060191,-.035193,0.0*
1,1,.006,-.060191,-.035193*
20,1,.006,-.060191,-.035193,-.065665,-.027375,0.0*
1,1,.006,-.065665,-.027375*
20,1,.006,-.065665,-.027375,-.069698,-.018726,0.0*
1,1,.006,-.069698,-.018726*
20,1,.006,-.069698,-.018726,-.072168,-.009507,0.0*
1,1,.006,-.072168,-.009507*
20,1,.006,-.072168,-.009507,-.073,0.0,0.0*
1,1,.006,-.073,0.0*
20,1,.006,-.073,0.0,-.072168,.009507,0.0*
1,1,.006,-.072168,.009507*
20,1,.006,-.072168,.009507,-.069698,.018726,0.0*
1,1,.006,-.069698,.018726*
20,1,.006,-.069698,.018726,-.065665,.027375,0.0*
1,1,.006,-.065665,.027375*
20,1,.006,-.065665,.027375,-.060191,.035193,0.0*
1,1,.006,-.060191,.035193*
20,1,.006,-.060191,.035193,-.053443,.041941,0.0*
1,1,.006,-.053443,.041941*
20,1,.006,-.053443,.041941,-.045625,.047415,0.0*
1,1,.006,-.045625,.047415*
20,1,.006,-.045625,.047415,-.036976,.051448,0.0*
1,1,.006,-.036976,.051448*
20,1,.006,-.036976,.051448,-.027757,.053918,0.0*
1,1,.006,-.027757,.053918*
20,1,.006,-.027757,.053918,-.01825,.05475,0.0*
1,1,.006,-.01825,.05475*
1,1,.006,0.0,-.02737*
20,1,.006,0.0,-.02737,.00639,-.02646,0.0*
1,1,.006,.00639,-.02646*
20,1,.006,.00639,-.02646,.01369,-.02372,0.0*
1,1,.006,.01369,-.02372*
20,1,.006,.01369,-.02372,.01826,-.01916,0.0*
1,1,.006,.01826,-.01916*
20,1,.006,.01826,-.01916,.02008,-.01277,0.0*
1,1,.006,.02008,-.01277*
20,1,.006,.02008,-.01277,.01826,-.00638,0.0*
1,1,.006,.01826,-.00638*
20,1,.006,.01826,-.00638,.01278,-.00091,0.0*
1,1,.006,.01278,-.00091*
20,1,.006,.01278,-.00091,.00457,.00183,0.0*
1,1,.006,.00457,.00183*
20,1,.006,.00457,.00183,-.00456,.00183,0.0*
1,1,.006,-.00456,.00183*
20,1,.006,-.00456,.00183,-.01003,.00366,0.0*
1,1,.006,-.01003,.00366*
20,1,.006,-.01003,.00366,-.0146,.00822,0.0*
1,1,.006,-.0146,.00822*
20,1,.006,-.0146,.00822,-.01642,.0146,0.0*
1,1,.006,-.01642,.0146*
20,1,.006,-.01642,.0146,-.01368,.02099,0.0*
1,1,.006,-.01368,.02099*
20,1,.006,-.01368,.02099,-.0073,.02556,0.0*
1,1,.006,-.0073,.02556*
20,1,.006,-.0073,.02556,0.0,.02738,0.0*
1,1,.006,0.0,.02738*
20,1,.006,0.0,.02738,.0073,.02556,0.0*
1,1,.006,.0073,.02556*
20,1,.006,.0073,.02556,.01369,.02099,0.0*
1,1,.006,.01369,.02099*
20,1,.006,.01369,.02099,.01643,.0146,0.0*
1,1,.006,.01643,.0146*
20,1,.006,.01643,.0146,.0146,.00822,0.0*
1,1,.006,.0146,.00822*
20,1,.006,.0146,.00822,.01004,.00366,0.0*
1,1,.006,.01004,.00366*
20,1,.006,.01004,.00366,.00457,.00183,0.0*
1,1,.006,.00457,.00183*
20,1,.006,.00457,.00183,-.00456,.00183,0.0*
1,1,.006,-.00456,.00183*
20,1,.006,-.00456,.00183,-.01277,-.00091,0.0*
1,1,.006,-.01277,-.00091*
20,1,.006,-.01277,-.00091,-.01825,-.00638,0.0*
1,1,.006,-.01825,-.00638*
20,1,.006,-.01825,-.00638,-.02007,-.01277,0.0*
1,1,.006,-.02007,-.01277*
20,1,.006,-.02007,-.01277,-.01825,-.01916,0.0*
1,1,.006,-.01825,-.01916*
20,1,.006,-.01825,-.01916,-.01368,-.02372,0.0*
1,1,.006,-.01368,-.02372*
20,1,.006,-.01368,-.02372,-.00638,-.02646,0.0*
1,1,.006,-.00638,-.02646*
20,1,.006,-.00638,-.02646,0.0,-.02737,0.0*
1,1,.006,0.0,-.02737*
%
%ADD18MACRO18*%
%AMMACRO17*
1,1,.006,0.0,.0785*
20,1,.006,0.0,.0785,-.067983,.03925,0.0*
1,1,.006,-.067983,.03925*
20,1,.006,-.067983,.03925,-.067983,-.03925,0.0*
1,1,.006,-.067983,-.03925*
20,1,.006,-.067983,-.03925,0.0,-.0785,0.0*
1,1,.006,0.0,-.0785*
20,1,.006,0.0,-.0785,.067983,-.03925,0.0*
1,1,.006,.067983,-.03925*
20,1,.006,.067983,-.03925,.067983,.03925,0.0*
1,1,.006,.067983,.03925*
20,1,.006,.067983,.03925,0.0,.0785,0.0*
1,1,.006,0.0,.0785*
1,1,.006,.0157,-.03925*
20,1,.006,.0157,-.03925,.0157,.03925,0.0*
1,1,.006,.0157,.03925*
20,1,.006,.0157,.03925,-.03271,-.01701,0.0*
1,1,.006,-.03271,-.01701*
20,1,.006,-.03271,-.01701,.03271,-.01701,0.0*
1,1,.006,.03271,-.01701*
%
%ADD17MACRO17*%
%AMMACRO12*
1,1,.006,0.0,.0455*
20,1,.006,0.0,.0455,.0455,-.0455,0.0*
1,1,.006,.0455,-.0455*
20,1,.006,.0455,-.0455,-.0455,-.0455,0.0*
1,1,.006,-.0455,-.0455*
20,1,.006,-.0455,-.0455,0.0,.0455,0.0*
1,1,.006,0.0,.0455*
1,1,.006,-.00152,-.02275*
20,1,.006,-.00152,-.02275,0.0,-.01289,0.0*
1,1,.006,0.0,-.01289*
20,1,.006,0.0,-.01289,.00228,-.00455,0.0*
1,1,.006,.00228,-.00455*
20,1,.006,.00228,-.00455,.00531,.00303,0.0*
1,1,.006,.00531,.00303*
20,1,.006,.00531,.00303,.0091,.01137,0.0*
1,1,.006,.0091,.01137*
20,1,.006,.0091,.01137,.01517,.02275,0.0*
1,1,.006,.01517,.02275*
20,1,.006,.01517,.02275,-.01517,.02275,0.0*
1,1,.006,-.01517,.02275*
%
%ADD12MACRO12*%
%ADD19C,.02*%
%ADD20C,.006*%
G75*
%LPD*%
G75*
G54D10*
X-39052Y28742D03*
X-43327Y310478D03*
X-39686Y917251D03*
X-38801Y1082342D03*
X-44886Y1294251D03*
X-43103Y1928864D03*
X1071932Y32074D03*
X1074813Y1348051D03*
X1076613Y1740651D03*
X1074813Y1957551D03*
X1281550Y1759350D03*
G54D20*
G01X-89222Y-207897D02*
Y-190397D01*
G01X-80052D02*
Y-207897D01*
G01Y-199147D02*
X-89222D01*
G01X-67137Y-207897D02*
X-68447Y-207605D01*
X-69757Y-206439D01*
X-70631Y-204397D01*
X-71067Y-202064D01*
X-70631Y-199730D01*
X-69757Y-197689D01*
X-68447Y-196522D01*
X-67137Y-196231D01*
X-65827Y-196522D01*
X-64517Y-197689D01*
X-63644Y-199730D01*
X-63425Y-202064D01*
X-63644Y-204397D01*
X-64517Y-206439D01*
X-65827Y-207605D01*
X-67137Y-207897D01*
G01X-53349D02*
Y-196231D01*
G01Y-199147D02*
X-52475Y-197689D01*
X-51165Y-196522D01*
X-49419Y-196231D01*
X-47891Y-196522D01*
X-46580Y-197689D01*
X-45925Y-199730D01*
Y-207897D01*
G01X-35412Y-200022D02*
X-28425D01*
X-29080Y-197980D01*
X-30172Y-196814D01*
X-31700Y-196231D01*
X-33229Y-196522D01*
X-34539Y-197397D01*
X-35412Y-199439D01*
X-35849Y-201189D01*
Y-202939D01*
X-35412Y-204689D01*
X-34320Y-206439D01*
X-33010Y-207605D01*
X-31482Y-207897D01*
X-29954Y-207314D01*
X-28425Y-205564D01*
G01X-19222Y-213147D02*
X-17912Y-213730D01*
X-16165Y-213147D01*
X-15074Y-211981D01*
X-14200Y-210522D01*
X-12891Y-205856D01*
X-10052Y-196231D01*
G01X-17039D02*
X-12891Y-205856D01*
G01X22109Y-198564D02*
X22983Y-197689D01*
X23638Y-196231D01*
X24075Y-194188D01*
X23638Y-192439D01*
X22765Y-191272D01*
X21236Y-190397D01*
X15341D01*
Y-207897D01*
X22546D01*
X24075Y-206731D01*
X24948Y-204980D01*
X25385Y-202939D01*
X24948Y-200897D01*
X23638Y-199147D01*
X22109Y-198564D01*
X15341D01*
G01X41793Y-207897D02*
Y-196231D01*
G01Y-198272D02*
X40920Y-197106D01*
X39609Y-196522D01*
X38081Y-196231D01*
X36553Y-196814D01*
X35243Y-197980D01*
X34369Y-199730D01*
X33933Y-202064D01*
X34369Y-204397D01*
X35243Y-206147D01*
X36553Y-207314D01*
X38081Y-207897D01*
X39609Y-207605D01*
X40920Y-206731D01*
X41793Y-205564D01*
G01X59293Y-190397D02*
Y-207897D01*
G01Y-205273D02*
X58420Y-206731D01*
X57109Y-207605D01*
X55581Y-207897D01*
X53835Y-207314D01*
X52525Y-205856D01*
X51651Y-204106D01*
X51433Y-202064D01*
X51651Y-200022D01*
X52525Y-198272D01*
X53835Y-196814D01*
X55581Y-196231D01*
X57109Y-196522D01*
X58201Y-197106D01*
X59293Y-198272D01*
G01X69806Y-212272D02*
X71335Y-213439D01*
X73081Y-213730D01*
X74609Y-213439D01*
X75920Y-211981D01*
X76793Y-209939D01*
Y-196231D01*
G01Y-198564D02*
X75920Y-197397D01*
X74609Y-196522D01*
X73081Y-196231D01*
X71335Y-196814D01*
X70243Y-197980D01*
X69369Y-200022D01*
X68933Y-202064D01*
X69151Y-203814D01*
X70025Y-205856D01*
X71335Y-207314D01*
X73081Y-207897D01*
X74391Y-207605D01*
X75920Y-206439D01*
X76793Y-205273D01*
G01X87088Y-200022D02*
X94075D01*
X93420Y-197980D01*
X92328Y-196814D01*
X90800Y-196231D01*
X89271Y-196522D01*
X87961Y-197397D01*
X87088Y-199439D01*
X86651Y-201189D01*
Y-202939D01*
X87088Y-204689D01*
X88180Y-206439D01*
X89490Y-207605D01*
X91018Y-207897D01*
X92546Y-207314D01*
X94075Y-205564D01*
G01X104806Y-207897D02*
Y-196231D01*
G01Y-198564D02*
X105898Y-197397D01*
X106990Y-196522D01*
X108518Y-196231D01*
X109609Y-196522D01*
X110920Y-197397D01*
G01X138060Y-207897D02*
Y-190397D01*
X142426D01*
X144173Y-191272D01*
X145483Y-192439D01*
X146575Y-194188D01*
X147448Y-196231D01*
X147666Y-199147D01*
X147448Y-202064D01*
X146575Y-204106D01*
X145483Y-205856D01*
X144173Y-207022D01*
X142426Y-207897D01*
X138060D01*
G01X155996D02*
Y-190397D01*
X161236D01*
X162983Y-191272D01*
X164293Y-193314D01*
X164730Y-195647D01*
X164293Y-197980D01*
X163201Y-199730D01*
X161236Y-200606D01*
X155996D01*
G01X179609Y-198564D02*
X180483Y-197689D01*
X181138Y-196231D01*
X181575Y-194188D01*
X181138Y-192439D01*
X180265Y-191272D01*
X178736Y-190397D01*
X172841D01*
Y-207897D01*
X180046D01*
X181575Y-206731D01*
X182448Y-204980D01*
X182885Y-202939D01*
X182448Y-200897D01*
X181138Y-199147D01*
X179609Y-198564D01*
X172841D01*
G01X208496Y-190397D02*
Y-207897D01*
X217230D01*
G01X230363D02*
X229053Y-207605D01*
X227743Y-206439D01*
X226869Y-204397D01*
X226433Y-202064D01*
X226869Y-199730D01*
X227743Y-197689D01*
X229053Y-196522D01*
X230363Y-196231D01*
X231673Y-196522D01*
X232983Y-197689D01*
X233856Y-199730D01*
X234075Y-202064D01*
X233856Y-204397D01*
X232983Y-206439D01*
X231673Y-207605D01*
X230363Y-207897D01*
G01X242404Y-196231D02*
X245025Y-207897D01*
X247863Y-196231D01*
X250701Y-207897D01*
X253322Y-196231D01*
G01X278496Y-190397D02*
Y-207897D01*
X287230D01*
G01X300363D02*
X299053Y-207605D01*
X297743Y-206439D01*
X296869Y-204397D01*
X296433Y-202064D01*
X296869Y-199730D01*
X297743Y-197689D01*
X299053Y-196522D01*
X300363Y-196231D01*
X301673Y-196522D01*
X302983Y-197689D01*
X303856Y-199730D01*
X304075Y-202064D01*
X303856Y-204397D01*
X302983Y-206439D01*
X301673Y-207605D01*
X300363Y-207897D01*
G01X314588Y-205856D02*
X315680Y-207022D01*
X317208Y-207897D01*
X318518D01*
X319828Y-207314D01*
X320701Y-206439D01*
X321138Y-205273D01*
X320920Y-203522D01*
X320046Y-202647D01*
X316116Y-200897D01*
X315243Y-198855D01*
X315680Y-197397D01*
X316553Y-196522D01*
X317863Y-196231D01*
X319173Y-196522D01*
X320483Y-197397D01*
G01X332088Y-205856D02*
X333180Y-207022D01*
X334708Y-207897D01*
X336018D01*
X337328Y-207314D01*
X338201Y-206439D01*
X338638Y-205273D01*
X338420Y-203522D01*
X337546Y-202647D01*
X333616Y-200897D01*
X332743Y-198855D01*
X333180Y-197397D01*
X334053Y-196522D01*
X335363Y-196231D01*
X336673Y-196522D01*
X337983Y-197397D01*
G01X-78741Y15000D02*
G03X-63741Y0I15000J0D01*
G01X-78741Y15000D02*
Y120047D01*
G01X-63741Y135047D02*
G03X-78741Y120047I0J-15000D01*
G01Y298866D02*
G03X-63741Y283866I15000J0D01*
G01X-78741Y319646D02*
Y298866D01*
G01X-63741Y334646D02*
G03X-78741Y319646I0J-15000D01*
G01Y908315D02*
G03X-63741Y893315I15000J0D01*
G01X-78741Y908315D02*
Y1104299D01*
G01X-63741Y1119299D02*
G03X-78741Y1104299I0J-15000D01*
G01Y1283118D02*
G03X-63741Y1268118I15000J0D01*
G01X-78741Y1304285D02*
Y1283118D01*
G01X-63741Y1319285D02*
G03X-78741Y1304285I0J-15000D01*
G01Y1892953D02*
G03X-63741Y1877953I15000J0D01*
G01X-78741Y1892953D02*
Y1977126D01*
G01X-63741Y1992126D02*
G03X-78741Y1977126I0J-15000D01*
G01X19882Y1197834D02*
X1969D01*
X0Y1195865D01*
Y832479D01*
X1969Y830511D01*
X19882D01*
G02Y823030I0J-3741D01*
G01X1969D01*
X0Y821062D01*
Y423030D01*
X1969Y421062D01*
X19882D01*
G02Y413582I0J-3740D01*
G01X1969D01*
X0Y411613D01*
Y223030D01*
X1969Y221062D01*
X19882D01*
G02Y213582I0J-3740D01*
G01X1969D01*
X0Y211613D01*
Y3936D01*
G03X3937Y-1I3937J0D01*
G01X1029528D01*
G03X1033465Y3936I0J3937D01*
G01Y1424881D01*
X1029528Y1428818D01*
X1024213D01*
G02X1019291Y1433739I-1J4921D01*
G01Y1607932D01*
X1015354Y1611869D01*
X989744D01*
G02Y1616082I0J2107D01*
G01X1015354D01*
X1019291Y1620019D01*
Y1676495D01*
G02X1024213Y1681416I4921J0D01*
G01X1029528D01*
X1033465Y1685353D01*
Y1988188D01*
G03X1029528Y1992125I-3937J0D01*
G01X3937D01*
G03X0Y1988188I0J-3937D01*
G01Y1816731D01*
X1969Y1814763D01*
X19882D01*
G02Y1807282I0J-3741D01*
G01X1969D01*
X0Y1805314D01*
Y1407282D01*
X1969Y1405314D01*
X19882D01*
G02Y1397834I0J-3740D01*
G01X1969D01*
X0Y1395865D01*
Y1207282D01*
X1969Y1205314D01*
X19882D01*
G02Y1197834I0J-3740D01*
G01X-7875Y0D02*
X-63741D01*
G01X-7875Y41772D02*
Y104969D01*
G01Y17252D02*
Y0D01*
G01Y41772D02*
G03X-1I3937J-1D01*
G01Y17213D02*
G03X-7875I-3937J0D01*
G01Y41772D02*
G03X-1I3937J-1D01*
G01Y17213D02*
G03X-7875I-3937J0D01*
G01Y129516D02*
Y135047D01*
G01D02*
X-63741D01*
G01X-7875Y129516D02*
G03X-1I3937J0D01*
G01Y104958D02*
G03X-7875I-3937J0D01*
G01Y283866D02*
Y300383D01*
G01X-19814Y283866D02*
X-63741D01*
G01X-7875D02*
X-19814D01*
G01X-1Y300383D02*
G03X-7875I-3937J0D01*
G01Y331986D02*
Y324003D01*
G01Y331986D02*
Y334646D01*
G01D02*
X-63741D01*
G01X-7875Y324003D02*
G03X-1I3937J0D01*
G01X-7875Y905988D02*
Y893315D01*
G01D02*
X-63741D01*
G01X-7875Y1069005D02*
Y933234D01*
G01D02*
G03X-1I3937J0D01*
G01Y905988D02*
G03X-7875I-3937J0D01*
G01Y1108863D02*
Y1119299D01*
G01X-19126D02*
X-7875D01*
G01X-15749D02*
X-63741D01*
G01X-7875Y1106300D02*
Y1111425D01*
G01Y1106300D02*
Y1092625D01*
G01D02*
G03X-1I3937J0D01*
G01Y1069005D02*
G03X-7875I-3937J0D01*
G01X-17894Y1268118D02*
X-7875D01*
G01Y1278280D02*
Y1268118D01*
G01Y1280567D02*
Y1275992D01*
G01X-15749Y1268118D02*
X-63741D01*
G01X-7875Y1309889D02*
G03X-1I3937J0D01*
G01Y1280567D02*
G03X-7875I-3937J0D01*
G01Y1309889D02*
G03X-1I3937J0D01*
G01Y1280567D02*
G03X-7875I-3937J0D01*
G01Y1309889D02*
Y1319285D01*
G01D02*
X-63741D01*
G01X-7875Y1889223D02*
Y1877953D01*
G01D02*
X-63741D01*
G01X-7875Y1912843D02*
Y1962926D01*
G01Y1912843D02*
G03X-1I3937J0D01*
G01Y1889223D02*
G03X-7875I-3937J0D01*
G01Y1912843D02*
G03X-1I3937J0D01*
G01Y1889223D02*
G03X-7875I-3937J0D01*
G01X-1Y1962926D02*
G03X-7875I-3937J0D01*
G01X-1D02*
G03X-7875I-3937J0D01*
G01Y1986546D02*
Y1992126D01*
G01D02*
X-63741D01*
G01X-7875Y1986546D02*
G03X-1I3937J0D01*
G01X-7875D02*
G03X-1I3937J0D01*
G01X94686Y-164897D02*
Y-147397D01*
X100363Y-161980D01*
X106040Y-147397D01*
Y-164897D01*
G01X117863D02*
X116553Y-164605D01*
X115243Y-163439D01*
X114369Y-161397D01*
X113933Y-159064D01*
X114369Y-156730D01*
X115243Y-154689D01*
X116553Y-153522D01*
X117863Y-153231D01*
X119173Y-153522D01*
X120483Y-154689D01*
X121356Y-156730D01*
X121575Y-159064D01*
X121356Y-161397D01*
X120483Y-163439D01*
X119173Y-164605D01*
X117863Y-164897D01*
G01X139293Y-147397D02*
Y-164897D01*
G01Y-162273D02*
X138420Y-163731D01*
X137109Y-164605D01*
X135581Y-164897D01*
X133835Y-164314D01*
X132525Y-162856D01*
X131651Y-161106D01*
X131433Y-159064D01*
X131651Y-157022D01*
X132525Y-155272D01*
X133835Y-153814D01*
X135581Y-153231D01*
X137109Y-153522D01*
X138201Y-154106D01*
X139293Y-155272D01*
G01X149588Y-157022D02*
X156575D01*
X155920Y-154980D01*
X154828Y-153814D01*
X153300Y-153231D01*
X151771Y-153522D01*
X150461Y-154397D01*
X149588Y-156439D01*
X149151Y-158189D01*
Y-159939D01*
X149588Y-161689D01*
X150680Y-163439D01*
X151990Y-164605D01*
X153518Y-164897D01*
X155046Y-164314D01*
X156575Y-162564D01*
G01X170363Y-164897D02*
Y-147397D01*
G01X68771Y18647D02*
Y27074D01*
G01X67271Y23647D02*
X68771Y18647D01*
X70271Y23647D01*
X67271D01*
G01X66748Y18647D02*
X71048D01*
G02Y15447I0J-1600D01*
G01X66748D01*
G02Y18647I0J1600D01*
G01X67218Y183670D02*
X68718Y188670D01*
X70218Y183670D01*
X67218D01*
G01X68718Y188670D02*
Y180243D01*
G01X66748Y191875D02*
X71048D01*
G02Y188675I0J-1600D01*
G01X66748D01*
G02Y191875I0J1600D01*
G01X68771Y424159D02*
Y432586D01*
G01X67271Y429159D02*
X68771Y424159D01*
X70271Y429159D01*
X67271D01*
G01X66748Y424159D02*
X71048D01*
G02Y420959I0J-1600D01*
G01X66748D01*
G02Y424159I0J1600D01*
G01X67218Y589182D02*
X68718Y594182D01*
X70218Y589182D01*
X67218D01*
G01X68718Y594182D02*
Y585755D01*
G01X66748Y597387D02*
X71048D01*
G02Y594187I0J-1600D01*
G01X66748D01*
G02Y597387I0J1600D01*
G01X68771Y829671D02*
Y838098D01*
G01X67271Y834671D02*
X68771Y829671D01*
X70271Y834671D01*
X67271D01*
G01X66748Y829671D02*
X71048D01*
G02Y826471I0J-1600D01*
G01X66748D01*
G02Y829671I0J1600D01*
G01X67218Y994694D02*
X68718Y999694D01*
X70218Y994694D01*
X67218D01*
G01X68718Y999694D02*
Y991267D01*
G01X66748Y1002899D02*
X71048D01*
G02Y999699I0J-1600D01*
G01X66748D01*
G02Y1002899I0J1600D01*
G01X68771Y1235183D02*
Y1243610D01*
G01X67271Y1240183D02*
X68771Y1235183D01*
X70271Y1240183D01*
X67271D01*
G01X66748Y1235183D02*
X71048D01*
G02Y1231983I0J-1600D01*
G01X66748D01*
G02Y1235183I0J1600D01*
G01X67218Y1400206D02*
X68718Y1405206D01*
X70218Y1400206D01*
X67218D01*
G01X68718Y1405206D02*
Y1396779D01*
G01X66748Y1408411D02*
X71048D01*
G02Y1405211I0J-1600D01*
G01X66748D01*
G02Y1408411I0J1600D01*
G01Y1640695D02*
X71048D01*
G02Y1637495I0J-1600D01*
G01X66748D01*
G02Y1640695I0J1600D01*
G01X68771D02*
Y1649122D01*
G01X67271Y1645695D02*
X68771Y1640695D01*
X70271Y1645695D01*
X67271D01*
G01X68718Y1810718D02*
Y1802291D01*
G01X67218Y1805718D02*
X68718Y1810718D01*
X70218Y1805718D01*
X67218D01*
G01X66748Y1813923D02*
X71048D01*
G02Y1810723I0J-1600D01*
G01X66748D01*
G02Y1813923I0J1600D01*
G01X169003Y186408D02*
X167503Y181408D01*
X166003Y186408D01*
X169003D01*
G01X167503Y181408D02*
Y189835D01*
G01X169473Y178203D02*
X165173D01*
G02Y181403I0J1600D01*
G01X169473D01*
G02Y178203I0J-1600D01*
G01X167450Y351431D02*
Y343004D01*
G01X168950Y346431D02*
X167450Y351431D01*
X165950Y346431D01*
X168950D01*
G01X169473Y351431D02*
X165173D01*
G02Y354631I0J1600D01*
G01X169473D01*
G02Y351431I0J-1600D01*
G01X169003Y591920D02*
X167503Y586920D01*
X166003Y591920D01*
X169003D01*
G01X167503Y586920D02*
Y595347D01*
G01X169473Y583715D02*
X165173D01*
G02Y586915I0J1600D01*
G01X169473D01*
G02Y583715I0J-1600D01*
G01X167450Y756943D02*
Y748516D01*
G01X168950Y751943D02*
X167450Y756943D01*
X165950Y751943D01*
X168950D01*
G01X169473Y756943D02*
X165173D01*
G02Y760143I0J1600D01*
G01X169473D01*
G02Y756943I0J-1600D01*
G01X169003Y997432D02*
X167503Y992432D01*
X166003Y997432D01*
X169003D01*
G01X167503Y992432D02*
Y1000859D01*
G01X169473Y989227D02*
X165173D01*
G02Y992427I0J1600D01*
G01X169473D01*
G02Y989227I0J-1600D01*
G01X167450Y1162455D02*
Y1154028D01*
G01X168950Y1157455D02*
X167450Y1162455D01*
X165950Y1157455D01*
X168950D01*
G01X169473Y1162455D02*
X165173D01*
G02Y1165655I0J1600D01*
G01X169473D01*
G02Y1162455I0J-1600D01*
G01X169003Y1402944D02*
X167503Y1397944D01*
X166003Y1402944D01*
X169003D01*
G01X167503Y1397944D02*
Y1406371D01*
G01X169473Y1394739D02*
X165173D01*
G02Y1397939I0J1600D01*
G01X169473D01*
G02Y1394739I0J-1600D01*
G01X167450Y1567967D02*
Y1559540D01*
G01X168950Y1562967D02*
X167450Y1567967D01*
X165950Y1562967D01*
X168950D01*
G01X169473Y1567967D02*
X165173D01*
G02Y1571167I0J1600D01*
G01X169473D01*
G02Y1567967I0J-1600D01*
G01X169003Y1808456D02*
X167503Y1803456D01*
X166003Y1808456D01*
X169003D01*
G01X167503Y1803456D02*
Y1811883D01*
G01X169473Y1800251D02*
X165173D01*
G02Y1803451I0J1600D01*
G01X169473D01*
G02Y1800251I0J-1600D01*
G01X167450Y1973479D02*
Y1965052D01*
G01X168950Y1968479D02*
X167450Y1973479D01*
X165950Y1968479D01*
X168950D01*
G01X169473Y1973479D02*
X165173D01*
G02Y1976679I0J1600D01*
G01X169473D01*
G02Y1973479I0J-1600D01*
G01X376163Y-209897D02*
Y-192397D01*
X373543Y-195897D01*
G01Y-209897D02*
X378783D01*
G01X396283D02*
Y-192397D01*
X388204Y-204939D01*
X399122D01*
G01X406360Y-207273D02*
X407669Y-208731D01*
X409198Y-209605D01*
X411163Y-209897D01*
X413128Y-209314D01*
X414656Y-208147D01*
X415748Y-206106D01*
X415966Y-203772D01*
X415530Y-201439D01*
X414438Y-199980D01*
X412909Y-198814D01*
X411381Y-198522D01*
X409853Y-198814D01*
X407888Y-199980D01*
X408543Y-192397D01*
X414438D01*
G01X431283Y-209897D02*
Y-192397D01*
X423204Y-204939D01*
X434122D01*
G01X441360Y-207273D02*
X442669Y-208731D01*
X444198Y-209605D01*
X446163Y-209897D01*
X448128Y-209314D01*
X449656Y-208147D01*
X450748Y-206106D01*
X450966Y-203772D01*
X450530Y-201439D01*
X449438Y-199980D01*
X447909Y-198814D01*
X446381Y-198522D01*
X444853Y-198814D01*
X442888Y-199980D01*
X443543Y-192397D01*
X449438D01*
G01X363046Y-164897D02*
Y-147397D01*
X368286D01*
X370033Y-148272D01*
X371343Y-150314D01*
X371780Y-152647D01*
X371343Y-154980D01*
X370251Y-156730D01*
X368286Y-157606D01*
X363046D01*
G01X389716Y-148856D02*
X388406Y-147980D01*
X386878Y-147397D01*
X385131D01*
X383166Y-148272D01*
X381638Y-149730D01*
X380546Y-151481D01*
X379673Y-154397D01*
X379454Y-157022D01*
X379891Y-159647D01*
X380546Y-161397D01*
X381856Y-163147D01*
X383385Y-164314D01*
X384913Y-164897D01*
X386441D01*
X387970Y-164314D01*
X389280Y-163439D01*
X390372Y-162273D01*
G01X404159Y-155564D02*
X405033Y-154689D01*
X405688Y-153231D01*
X406125Y-151188D01*
X405688Y-149439D01*
X404815Y-148272D01*
X403286Y-147397D01*
X397391D01*
Y-164897D01*
X404596D01*
X406125Y-163731D01*
X406998Y-161980D01*
X407435Y-159939D01*
X406998Y-157897D01*
X405688Y-156147D01*
X404159Y-155564D01*
X397391D01*
G01X413363Y-170730D02*
X426463D01*
G01X432391Y-164897D02*
Y-147397D01*
X442435Y-164897D01*
Y-147397D01*
G01X454913Y-164897D02*
X453166Y-164605D01*
X451638Y-163439D01*
X450328Y-161689D01*
X449454Y-159647D01*
X449018Y-157314D01*
Y-154980D01*
X449454Y-152647D01*
X450328Y-150605D01*
X451638Y-148856D01*
X453166Y-147689D01*
X454913Y-147397D01*
X456659Y-147689D01*
X458188Y-148856D01*
X459498Y-150605D01*
X460372Y-152647D01*
X460808Y-154980D01*
Y-157314D01*
X460372Y-159647D01*
X459498Y-161689D01*
X458188Y-163439D01*
X456659Y-164605D01*
X454913Y-164897D01*
G01X505754Y-147397D02*
X511213Y-164897D01*
X516672Y-147397D01*
G01X533080Y-164897D02*
X524346D01*
Y-147397D01*
X533080D01*
G01X529586Y-155855D02*
X524346D01*
G01X541846Y-164897D02*
Y-147397D01*
X547305D01*
X549051Y-148272D01*
X550143Y-149439D01*
X550580Y-151772D01*
X550143Y-154106D01*
X548833Y-155564D01*
X547305Y-156439D01*
X541846D01*
G01X547305D02*
X550580Y-164897D01*
G01X563713Y-165480D02*
X563276Y-165189D01*
Y-164605D01*
X563713Y-164314D01*
X564150Y-164605D01*
Y-165189D01*
X563713Y-165480D01*
G01X524128Y-207564D02*
X525875Y-209022D01*
X527840Y-209897D01*
X529586D01*
X531333Y-209022D01*
X532643Y-207564D01*
X533298Y-205522D01*
X532861Y-203481D01*
X531770Y-201730D01*
X529805Y-200564D01*
X527185Y-199980D01*
X525656Y-198814D01*
X525001Y-196772D01*
X525438Y-194730D01*
X526530Y-193272D01*
X528058Y-192397D01*
X529586D01*
X531115Y-192980D01*
X532425Y-194439D01*
G01X540754Y-209897D02*
X546213Y-192397D01*
X551672Y-209897D01*
G01X549706Y-203772D02*
X542719D01*
G01X638860Y-209897D02*
Y-192397D01*
X643226D01*
X644973Y-193272D01*
X646283Y-194439D01*
X647375Y-196188D01*
X648248Y-198231D01*
X648466Y-201147D01*
X648248Y-204064D01*
X647375Y-206106D01*
X646283Y-207856D01*
X644973Y-209022D01*
X643226Y-209897D01*
X638860D01*
G01X656796D02*
Y-192397D01*
X662255D01*
X664001Y-193272D01*
X665093Y-194439D01*
X665530Y-196772D01*
X665093Y-199106D01*
X663783Y-200564D01*
X662255Y-201439D01*
X656796D01*
G01X662255D02*
X665530Y-209897D01*
G01X676043Y-192397D02*
X681283D01*
G01X678663D02*
Y-209897D01*
G01X676043D02*
X681283D01*
G01X691796Y-192397D02*
Y-209897D01*
X700530D01*
G01X709296Y-192397D02*
Y-209897D01*
X718030D01*
G01X630546Y-147397D02*
Y-164897D01*
X639280D01*
G01X656343D02*
Y-153231D01*
G01Y-155272D02*
X655470Y-154106D01*
X654159Y-153522D01*
X652631Y-153231D01*
X651103Y-153814D01*
X649793Y-154980D01*
X648919Y-156730D01*
X648483Y-159064D01*
X648919Y-161397D01*
X649793Y-163147D01*
X651103Y-164314D01*
X652631Y-164897D01*
X654159Y-164605D01*
X655470Y-163731D01*
X656343Y-162564D01*
G01X665328Y-170147D02*
X666638Y-170730D01*
X668385Y-170147D01*
X669476Y-168981D01*
X670350Y-167522D01*
X671659Y-162856D01*
X674498Y-153231D01*
G01X667511D02*
X671659Y-162856D01*
G01X684138Y-157022D02*
X691125D01*
X690470Y-154980D01*
X689378Y-153814D01*
X687850Y-153231D01*
X686321Y-153522D01*
X685011Y-154397D01*
X684138Y-156439D01*
X683701Y-158189D01*
Y-159939D01*
X684138Y-161689D01*
X685230Y-163439D01*
X686540Y-164605D01*
X688068Y-164897D01*
X689596Y-164314D01*
X691125Y-162564D01*
G01X701856Y-164897D02*
Y-153231D01*
G01Y-155564D02*
X702948Y-154397D01*
X704040Y-153522D01*
X705568Y-153231D01*
X706659Y-153522D01*
X707970Y-154397D01*
G01X719138Y-162856D02*
X720230Y-164022D01*
X721758Y-164897D01*
X723068D01*
X724378Y-164314D01*
X725251Y-163439D01*
X725688Y-162273D01*
X725470Y-160522D01*
X724596Y-159647D01*
X720666Y-157897D01*
X719793Y-155855D01*
X720230Y-154397D01*
X721103Y-153522D01*
X722413Y-153231D01*
X723723Y-153522D01*
X725033Y-154397D01*
G01X790596Y-209897D02*
Y-192397D01*
X796055D01*
X797801Y-193272D01*
X798893Y-194439D01*
X799330Y-196772D01*
X798893Y-199106D01*
X797583Y-200564D01*
X796055Y-201439D01*
X790596D01*
G01X796055D02*
X799330Y-209897D01*
G01X809188Y-202022D02*
X816175D01*
X815520Y-199980D01*
X814428Y-198814D01*
X812900Y-198231D01*
X811371Y-198522D01*
X810061Y-199397D01*
X809188Y-201439D01*
X808751Y-203189D01*
Y-204939D01*
X809188Y-206689D01*
X810280Y-208439D01*
X811590Y-209605D01*
X813118Y-209897D01*
X814646Y-209314D01*
X816175Y-207564D01*
G01X826033Y-209897D02*
Y-192397D01*
G01Y-201147D02*
X827125Y-199397D01*
X828435Y-198522D01*
X829745Y-198231D01*
X831709Y-198814D01*
X833020Y-199980D01*
X833893Y-202022D01*
Y-204355D01*
X833456Y-206689D01*
X832583Y-208439D01*
X831055Y-209605D01*
X829745Y-209897D01*
X828435Y-209605D01*
X827125Y-208731D01*
X826033Y-207273D01*
G01X844188Y-202022D02*
X851175D01*
X850520Y-199980D01*
X849428Y-198814D01*
X847900Y-198231D01*
X846371Y-198522D01*
X845061Y-199397D01*
X844188Y-201439D01*
X843751Y-203189D01*
Y-204939D01*
X844188Y-206689D01*
X845280Y-208439D01*
X846590Y-209605D01*
X848118Y-209897D01*
X849646Y-209314D01*
X851175Y-207564D01*
G01X868456Y-199689D02*
X866928Y-198522D01*
X865618Y-198231D01*
X863871Y-198814D01*
X862561Y-199980D01*
X861688Y-202022D01*
X861469Y-204064D01*
X861688Y-206106D01*
X862561Y-207856D01*
X863871Y-209314D01*
X865618Y-209897D01*
X867146Y-209314D01*
X868456Y-208147D01*
G01X885956Y-199689D02*
X884428Y-198522D01*
X883118Y-198231D01*
X881371Y-198814D01*
X880061Y-199980D01*
X879188Y-202022D01*
X878969Y-204064D01*
X879188Y-206106D01*
X880061Y-207856D01*
X881371Y-209314D01*
X883118Y-209897D01*
X884646Y-209314D01*
X885956Y-208147D01*
G01X903893Y-209897D02*
Y-198231D01*
G01Y-200272D02*
X903020Y-199106D01*
X901709Y-198522D01*
X900181Y-198231D01*
X898653Y-198814D01*
X897343Y-199980D01*
X896469Y-201730D01*
X896033Y-204064D01*
X896469Y-206397D01*
X897343Y-208147D01*
X898653Y-209314D01*
X900181Y-209897D01*
X901709Y-209605D01*
X903020Y-208731D01*
X903893Y-207564D01*
G01X781410Y-164897D02*
Y-147397D01*
X785776D01*
X787523Y-148272D01*
X788833Y-149439D01*
X789925Y-151188D01*
X790798Y-153231D01*
X791016Y-156147D01*
X790798Y-159064D01*
X789925Y-161106D01*
X788833Y-162856D01*
X787523Y-164022D01*
X785776Y-164897D01*
X781410D01*
G01X800438Y-157022D02*
X807425D01*
X806770Y-154980D01*
X805678Y-153814D01*
X804150Y-153231D01*
X802621Y-153522D01*
X801311Y-154397D01*
X800438Y-156439D01*
X800001Y-158189D01*
Y-159939D01*
X800438Y-161689D01*
X801530Y-163439D01*
X802840Y-164605D01*
X804368Y-164897D01*
X805896Y-164314D01*
X807425Y-162564D01*
G01X817938Y-162856D02*
X819030Y-164022D01*
X820558Y-164897D01*
X821868D01*
X823178Y-164314D01*
X824051Y-163439D01*
X824488Y-162273D01*
X824270Y-160522D01*
X823396Y-159647D01*
X819466Y-157897D01*
X818593Y-155855D01*
X819030Y-154397D01*
X819903Y-153522D01*
X821213Y-153231D01*
X822523Y-153522D01*
X823833Y-154397D01*
G01X838713Y-153231D02*
Y-164897D01*
G01Y-148564D02*
X838276Y-148272D01*
Y-147689D01*
X838713Y-147397D01*
X839150Y-147689D01*
Y-148272D01*
X838713Y-148564D01*
G01X853156Y-169272D02*
X854685Y-170439D01*
X856431Y-170730D01*
X857959Y-170439D01*
X859270Y-168981D01*
X860143Y-166939D01*
Y-153231D01*
G01Y-155564D02*
X859270Y-154397D01*
X857959Y-153522D01*
X856431Y-153231D01*
X854685Y-153814D01*
X853593Y-154980D01*
X852719Y-157022D01*
X852283Y-159064D01*
X852501Y-160814D01*
X853375Y-162856D01*
X854685Y-164314D01*
X856431Y-164897D01*
X857741Y-164605D01*
X859270Y-163439D01*
X860143Y-162273D01*
G01X870001Y-164897D02*
Y-153231D01*
G01Y-156147D02*
X870875Y-154689D01*
X872185Y-153522D01*
X873931Y-153231D01*
X875459Y-153522D01*
X876770Y-154689D01*
X877425Y-156730D01*
Y-164897D01*
G01X887938Y-157022D02*
X894925D01*
X894270Y-154980D01*
X893178Y-153814D01*
X891650Y-153231D01*
X890121Y-153522D01*
X888811Y-154397D01*
X887938Y-156439D01*
X887501Y-158189D01*
Y-159939D01*
X887938Y-161689D01*
X889030Y-163439D01*
X890340Y-164605D01*
X891868Y-164897D01*
X893396Y-164314D01*
X894925Y-162564D01*
G01X905656Y-164897D02*
Y-153231D01*
G01Y-155564D02*
X906748Y-154397D01*
X907840Y-153522D01*
X909368Y-153231D01*
X910459Y-153522D01*
X911770Y-154397D01*
G01X897349Y186408D02*
X895849Y181408D01*
X894349Y186408D01*
X897349D01*
G01X895849Y181408D02*
Y189835D01*
G01X897819Y178203D02*
X893519D01*
G02Y181403I0J1600D01*
G01X897819D01*
G02Y178203I0J-1600D01*
G01X895796Y351431D02*
Y343004D01*
G01X897296Y346431D02*
X895796Y351431D01*
X894296Y346431D01*
X897296D01*
G01X897819Y351431D02*
X893519D01*
G02Y354631I0J1600D01*
G01X897819D01*
G02Y351431I0J-1600D01*
G01X897349Y591920D02*
X895849Y586920D01*
X894349Y591920D01*
X897349D01*
G01X895849Y586920D02*
Y595347D01*
G01X897819Y583715D02*
X893519D01*
G02Y586915I0J1600D01*
G01X897819D01*
G02Y583715I0J-1600D01*
G01X895796Y756943D02*
Y748516D01*
G01X897296Y751943D02*
X895796Y756943D01*
X894296Y751943D01*
X897296D01*
G01X897819Y756943D02*
X893519D01*
G02Y760143I0J1600D01*
G01X897819D01*
G02Y756943I0J-1600D01*
G01X897349Y997432D02*
X895849Y992432D01*
X894349Y997432D01*
X897349D01*
G01X895849Y992432D02*
Y1000859D01*
G01X897819Y989227D02*
X893519D01*
G02Y992427I0J1600D01*
G01X897819D01*
G02Y989227I0J-1600D01*
G01X895796Y1162455D02*
Y1154028D01*
G01X897296Y1157455D02*
X895796Y1162455D01*
X894296Y1157455D01*
X897296D01*
G01X897819Y1162455D02*
X893519D01*
G02Y1165655I0J1600D01*
G01X897819D01*
G02Y1162455I0J-1600D01*
G01X897349Y1402944D02*
X895849Y1397944D01*
X894349Y1402944D01*
X897349D01*
G01X895849Y1397944D02*
Y1406371D01*
G01X897819Y1394739D02*
X893519D01*
G02Y1397939I0J1600D01*
G01X897819D01*
G02Y1394739I0J-1600D01*
G01X895796Y1567967D02*
Y1559540D01*
G01X897296Y1562967D02*
X895796Y1567967D01*
X894296Y1562967D01*
X897296D01*
G01X897819Y1567967D02*
X893519D01*
G02Y1571167I0J1600D01*
G01X897819D01*
G02Y1567967I0J-1600D01*
G01X897349Y1808456D02*
X895849Y1803456D01*
X894349Y1808456D01*
X897349D01*
G01X895849Y1803456D02*
Y1811883D01*
G01X897819Y1800251D02*
X893519D01*
G02Y1803451I0J1600D01*
G01X897819D01*
G02Y1800251I0J-1600D01*
G01X895796Y1973479D02*
Y1965052D01*
G01X897296Y1968479D02*
X895796Y1973479D01*
X894296Y1968479D01*
X897296D01*
G01X897819Y1973479D02*
X893519D01*
G02Y1976679I0J1600D01*
G01X897819D01*
G02Y1973479I0J-1600D01*
G01X952413Y-192397D02*
X950666Y-192980D01*
X949356Y-194439D01*
X948483Y-196188D01*
X947828Y-198522D01*
X947610Y-201147D01*
X947828Y-203772D01*
X948483Y-206106D01*
X949356Y-207856D01*
X950666Y-209314D01*
X952413Y-209897D01*
X954159Y-209314D01*
X955470Y-207856D01*
X956343Y-206106D01*
X956998Y-203772D01*
X957216Y-201147D01*
X956998Y-198522D01*
X956343Y-196188D01*
X955470Y-194439D01*
X954159Y-192980D01*
X952413Y-192397D01*
G01X969913Y-209897D02*
X971441Y-209605D01*
X973188Y-208731D01*
X974280Y-207273D01*
X974716Y-205230D01*
X974280Y-203189D01*
X972970Y-201439D01*
X971005Y-200564D01*
X968821D01*
X967511Y-199980D01*
X966419Y-198522D01*
X965983Y-196481D01*
X966638Y-194439D01*
X968166Y-192980D01*
X969913Y-192397D01*
X971659Y-192980D01*
X973188Y-194439D01*
X973843Y-196481D01*
X973406Y-198522D01*
X972315Y-199980D01*
X971005Y-200564D01*
X968821D01*
X966856Y-201439D01*
X965546Y-203189D01*
X965110Y-205230D01*
X965546Y-207273D01*
X966638Y-208731D01*
X968385Y-209605D01*
X969913Y-209897D01*
G01X983483Y-210480D02*
X991343Y-192397D01*
G01X1004913D02*
X1003166Y-192980D01*
X1001856Y-194439D01*
X1000983Y-196188D01*
X1000328Y-198522D01*
X1000110Y-201147D01*
X1000328Y-203772D01*
X1000983Y-206106D01*
X1001856Y-207856D01*
X1003166Y-209314D01*
X1004913Y-209897D01*
X1006659Y-209314D01*
X1007970Y-207856D01*
X1008843Y-206106D01*
X1009498Y-203772D01*
X1009716Y-201147D01*
X1009498Y-198522D01*
X1008843Y-196188D01*
X1007970Y-194439D01*
X1006659Y-192980D01*
X1004913Y-192397D01*
G01X1022413Y-209897D02*
Y-192397D01*
X1019793Y-195897D01*
G01Y-209897D02*
X1025033D01*
G01X1035983Y-210480D02*
X1043843Y-192397D01*
G01X1053265Y-195314D02*
X1054575Y-193564D01*
X1056103Y-192689D01*
X1057850Y-192397D01*
X1060033Y-192980D01*
X1061561Y-194439D01*
X1061998Y-196188D01*
X1061780Y-197939D01*
X1060906Y-199397D01*
X1056540Y-202314D01*
X1054575Y-204355D01*
X1053265Y-207273D01*
X1052828Y-209897D01*
X1061998D01*
G01X1074913Y-192397D02*
X1073166Y-192980D01*
X1071856Y-194439D01*
X1070983Y-196188D01*
X1070328Y-198522D01*
X1070110Y-201147D01*
X1070328Y-203772D01*
X1070983Y-206106D01*
X1071856Y-207856D01*
X1073166Y-209314D01*
X1074913Y-209897D01*
X1076659Y-209314D01*
X1077970Y-207856D01*
X1078843Y-206106D01*
X1079498Y-203772D01*
X1079716Y-201147D01*
X1079498Y-198522D01*
X1078843Y-196188D01*
X1077970Y-194439D01*
X1076659Y-192980D01*
X1074913Y-192397D01*
G01X1092413Y-209897D02*
Y-192397D01*
X1089793Y-195897D01*
G01Y-209897D02*
X1095033D01*
G01X1112533D02*
Y-192397D01*
X1104454Y-204939D01*
X1115372D01*
G01X1000110Y-164897D02*
Y-147397D01*
X1004476D01*
X1006223Y-148272D01*
X1007533Y-149439D01*
X1008625Y-151188D01*
X1009498Y-153231D01*
X1009716Y-156147D01*
X1009498Y-159064D01*
X1008625Y-161106D01*
X1007533Y-162856D01*
X1006223Y-164022D01*
X1004476Y-164897D01*
X1000110D01*
G01X1026343D02*
Y-153231D01*
G01Y-155272D02*
X1025470Y-154106D01*
X1024159Y-153522D01*
X1022631Y-153231D01*
X1021103Y-153814D01*
X1019793Y-154980D01*
X1018919Y-156730D01*
X1018483Y-159064D01*
X1018919Y-161397D01*
X1019793Y-163147D01*
X1021103Y-164314D01*
X1022631Y-164897D01*
X1024159Y-164605D01*
X1025470Y-163731D01*
X1026343Y-162564D01*
G01X1039913Y-147397D02*
Y-164897D01*
G01X1036856Y-153231D02*
X1042970D01*
G01X1054138Y-157022D02*
X1061125D01*
X1060470Y-154980D01*
X1059378Y-153814D01*
X1057850Y-153231D01*
X1056321Y-153522D01*
X1055011Y-154397D01*
X1054138Y-156439D01*
X1053701Y-158189D01*
Y-159939D01*
X1054138Y-161689D01*
X1055230Y-163439D01*
X1056540Y-164605D01*
X1058068Y-164897D01*
X1059596Y-164314D01*
X1061125Y-162564D01*
G01X1041337Y24677D02*
Y0D01*
G01Y217343D02*
Y48297D01*
G01Y0D02*
X1097204D01*
G01X1033463Y48297D02*
G03X1041337I3937J0D01*
G01Y24677D02*
G03X1033463I-3937J0D01*
G01Y48297D02*
G03X1041337I3937J0D01*
G01Y24677D02*
G03X1033463I-3937J0D01*
G01X1041337Y217343D02*
G03X1033463I-3937J0D01*
G01X1041337D02*
G03X1033463I-3937J0D01*
G01X1041337Y445039D02*
Y240963D01*
G01X1033463D02*
G03X1041337I3937J0D01*
G01X1033463D02*
G03X1041337I3937J0D01*
G01Y697474D02*
Y468601D01*
G01X1033463Y468659D02*
G03X1041337I3937J0D01*
G01Y445039D02*
G03X1033463I-3937J0D01*
G01Y468659D02*
G03X1041337I3937J0D01*
G01Y445039D02*
G03X1033463I-3937J0D01*
G01X1041337Y996851D02*
Y721093D01*
G01X1033463D02*
G03X1041337I3937J0D01*
G01Y697474D02*
G03X1033463I-3937J-1D01*
G01Y721093D02*
G03X1041337I3937J0D01*
G01Y697474D02*
G03X1033463I-3937J-1D01*
G01X1041337Y1344059D02*
Y1020472D01*
G01X1033463D02*
G03X1041337I3937J0D01*
G01Y996851D02*
G03X1033463I-3937J1D01*
G01Y1020472D02*
G03X1041337I3937J0D01*
G01Y996851D02*
G03X1033463I-3937J1D01*
G01X1041337Y1367679D02*
Y1393701D01*
G01X1033463Y1367679D02*
G03X1041337I3937J0D01*
G01Y1344059D02*
G03X1033463I-3937J0D01*
G01Y1367679D02*
G03X1041337I3937J0D01*
G01Y1344059D02*
G03X1033463I-3937J0D01*
G01X1041337Y1393701D02*
X1097204D01*
G01X1041337Y1733129D02*
Y1716535D01*
G01X1065042D02*
X1041337D01*
G01X1056337D02*
X1097204D01*
G01X1041337Y1739719D02*
Y1731535D01*
G01Y1959242D02*
Y1763311D01*
G01X1033463Y1763339D02*
G03X1041337I3937J0D01*
G01Y1739719D02*
G03X1033463I-3937J0D01*
G01Y1763339D02*
G03X1041337I3937J0D01*
G01Y1739719D02*
G03X1033463I-3937J0D01*
G01X1041337Y1959242D02*
G03X1033463I-3937J0D01*
G01X1041337D02*
G03X1033463I-3937J0D01*
G01X1041337Y1992126D02*
X1097204D01*
G01X1041337Y1982862D02*
Y1992126D01*
G01X1033463Y1982862D02*
G03X1041337I3937J0D01*
G01X1033463D02*
G03X1041337I3937J0D01*
G01X1112204Y648419D02*
Y15000D01*
G01X1097204Y0D02*
G03X1112204Y15000I0J15000D01*
G01Y656293D02*
G03Y648419I0J-3937D01*
G01Y1378701D02*
Y656293D01*
G01Y1378701D02*
G03X1097204Y1393701I-15000J0D01*
G01Y1716535D02*
G03X1112204Y1731535I0J15000D01*
G01Y1977126D02*
Y1731535D01*
G01Y1977126D02*
G03X1097204Y1992126I-15000J0D01*
G01X1237685Y1631000D02*
Y1643500D01*
X1244815Y1631000D01*
Y1643500D01*
G01X1253650Y1631000D02*
X1252720Y1631208D01*
X1251790Y1632041D01*
X1251170Y1633500D01*
X1250860Y1635167D01*
X1251170Y1636833D01*
X1251790Y1638292D01*
X1252720Y1639125D01*
X1253650Y1639333D01*
X1254580Y1639125D01*
X1255510Y1638292D01*
X1256130Y1636833D01*
X1256285Y1635167D01*
X1256130Y1633500D01*
X1255510Y1632041D01*
X1254580Y1631208D01*
X1253650Y1631000D01*
G01X1266050Y1643500D02*
Y1631000D01*
G01X1263880Y1639333D02*
X1268220D01*
G01X1276125Y1636625D02*
X1281085D01*
X1280620Y1638083D01*
X1279845Y1638917D01*
X1278760Y1639333D01*
X1277675Y1639125D01*
X1276745Y1638500D01*
X1276125Y1637042D01*
X1275815Y1635791D01*
Y1634542D01*
X1276125Y1633292D01*
X1276900Y1632041D01*
X1277830Y1631208D01*
X1278915Y1631000D01*
X1280000Y1631417D01*
X1281085Y1632666D01*
G01X1290850Y1630583D02*
X1290540Y1630792D01*
Y1631208D01*
X1290850Y1631417D01*
X1291160Y1631208D01*
Y1630792D01*
X1290850Y1630583D01*
G01Y1636208D02*
X1290540Y1636417D01*
Y1636833D01*
X1290850Y1637042D01*
X1291160Y1636833D01*
Y1636417D01*
X1290850Y1636208D01*
G01X1300150Y1631000D02*
Y1643500D01*
X1304025D01*
X1305265Y1642875D01*
X1306040Y1642042D01*
X1306350Y1640375D01*
X1306040Y1638708D01*
X1305110Y1637667D01*
X1304025Y1637042D01*
X1300150D01*
G01X1304025D02*
X1306350Y1631000D01*
G01X1313325Y1636625D02*
X1318285D01*
X1317820Y1638083D01*
X1317045Y1638917D01*
X1315960Y1639333D01*
X1314875Y1639125D01*
X1313945Y1638500D01*
X1313325Y1637042D01*
X1313015Y1635791D01*
Y1634542D01*
X1313325Y1633292D01*
X1314100Y1632041D01*
X1315030Y1631208D01*
X1316115Y1631000D01*
X1317200Y1631417D01*
X1318285Y1632666D01*
G01X1327120Y1631000D02*
Y1641625D01*
X1327430Y1642666D01*
X1328050Y1643292D01*
X1328980Y1643500D01*
X1329910Y1643083D01*
X1330375Y1642042D01*
G01X1328515Y1638500D02*
X1325415D01*
G01X1338125Y1636625D02*
X1343085D01*
X1342620Y1638083D01*
X1341845Y1638917D01*
X1340760Y1639333D01*
X1339675Y1639125D01*
X1338745Y1638500D01*
X1338125Y1637042D01*
X1337815Y1635791D01*
Y1634542D01*
X1338125Y1633292D01*
X1338900Y1632041D01*
X1339830Y1631208D01*
X1340915Y1631000D01*
X1342000Y1631417D01*
X1343085Y1632666D01*
G01X1350680Y1631000D02*
Y1639333D01*
G01Y1637667D02*
X1351455Y1638500D01*
X1352230Y1639125D01*
X1353315Y1639333D01*
X1354090Y1639125D01*
X1355020Y1638500D01*
G01X1377650Y1643500D02*
Y1631000D01*
G01X1375480Y1639333D02*
X1379820D01*
G01X1390050Y1631000D02*
X1389120Y1631208D01*
X1388190Y1632041D01*
X1387570Y1633500D01*
X1387260Y1635167D01*
X1387570Y1636833D01*
X1388190Y1638292D01*
X1389120Y1639125D01*
X1390050Y1639333D01*
X1390980Y1639125D01*
X1391910Y1638292D01*
X1392530Y1636833D01*
X1392685Y1635167D01*
X1392530Y1633500D01*
X1391910Y1632041D01*
X1390980Y1631208D01*
X1390050Y1631000D01*
G01X1411440D02*
Y1643500D01*
X1414540D01*
X1415780Y1642875D01*
X1416710Y1642042D01*
X1417485Y1640792D01*
X1418105Y1639333D01*
X1418260Y1637250D01*
X1418105Y1635167D01*
X1417485Y1633708D01*
X1416710Y1632458D01*
X1415780Y1631625D01*
X1414540Y1631000D01*
X1411440D01*
G01X1424150D02*
Y1643500D01*
X1428025D01*
X1429265Y1642875D01*
X1430040Y1642042D01*
X1430350Y1640375D01*
X1430040Y1638708D01*
X1429110Y1637667D01*
X1428025Y1637042D01*
X1424150D01*
G01X1428025D02*
X1430350Y1631000D01*
G01X1437790Y1643500D02*
X1441510D01*
G01X1439650D02*
Y1631000D01*
G01X1437790D02*
X1441510D01*
G01X1448950Y1643500D02*
Y1631000D01*
X1455150D01*
G01X1461350Y1643500D02*
Y1631000D01*
X1467550D01*
G01X1489250D02*
Y1643500D01*
G01X1504440Y1631000D02*
Y1639333D01*
G01Y1637875D02*
X1503820Y1638708D01*
X1502890Y1639125D01*
X1501805Y1639333D01*
X1500720Y1638917D01*
X1499790Y1638083D01*
X1499170Y1636833D01*
X1498860Y1635167D01*
X1499170Y1633500D01*
X1499790Y1632250D01*
X1500720Y1631417D01*
X1501805Y1631000D01*
X1502890Y1631208D01*
X1503820Y1631833D01*
X1504440Y1632666D01*
G01X1510795Y1627250D02*
X1511725Y1626833D01*
X1512965Y1627250D01*
X1513740Y1628083D01*
X1514360Y1629125D01*
X1515290Y1632458D01*
X1517305Y1639333D01*
G01X1512345D02*
X1515290Y1632458D01*
G01X1524125Y1636625D02*
X1529085D01*
X1528620Y1638083D01*
X1527845Y1638917D01*
X1526760Y1639333D01*
X1525675Y1639125D01*
X1524745Y1638500D01*
X1524125Y1637042D01*
X1523815Y1635791D01*
Y1634542D01*
X1524125Y1633292D01*
X1524900Y1632041D01*
X1525830Y1631208D01*
X1526915Y1631000D01*
X1528000Y1631417D01*
X1529085Y1632666D01*
G01X1536680Y1631000D02*
Y1639333D01*
G01Y1637667D02*
X1537455Y1638500D01*
X1538230Y1639125D01*
X1539315Y1639333D01*
X1540090Y1639125D01*
X1541020Y1638500D01*
G01X1562720Y1631000D02*
Y1641625D01*
X1563030Y1642666D01*
X1563650Y1643292D01*
X1564580Y1643500D01*
X1565510Y1643083D01*
X1565975Y1642042D01*
G01X1564115Y1638500D02*
X1561015D01*
G01X1576050Y1631000D02*
X1575120Y1631208D01*
X1574190Y1632041D01*
X1573570Y1633500D01*
X1573260Y1635167D01*
X1573570Y1636833D01*
X1574190Y1638292D01*
X1575120Y1639125D01*
X1576050Y1639333D01*
X1576980Y1639125D01*
X1577910Y1638292D01*
X1578530Y1636833D01*
X1578685Y1635167D01*
X1578530Y1633500D01*
X1577910Y1632041D01*
X1576980Y1631208D01*
X1576050Y1631000D01*
G01X1586280D02*
Y1639333D01*
G01Y1637667D02*
X1587055Y1638500D01*
X1587830Y1639125D01*
X1588915Y1639333D01*
X1589690Y1639125D01*
X1590620Y1638500D01*
G01X1616350Y1631000D02*
X1610150D01*
Y1643500D01*
X1616350D01*
G01X1613870Y1637458D02*
X1610150D01*
G01X1622550Y1643500D02*
Y1631000D01*
X1628750D01*
G01X1634950Y1643500D02*
Y1631000D01*
X1641150D01*
G01X1648590Y1643500D02*
X1652310D01*
G01X1650450D02*
Y1631000D01*
G01X1648590D02*
X1652310D01*
G01X1659750D02*
Y1643500D01*
X1663470D01*
X1664710Y1642875D01*
X1665640Y1641417D01*
X1665950Y1639750D01*
X1665640Y1638083D01*
X1664865Y1636833D01*
X1663470Y1636208D01*
X1659750D01*
G01X1671995Y1632666D02*
X1673235Y1631625D01*
X1674630Y1631000D01*
X1675870D01*
X1677110Y1631625D01*
X1678040Y1632666D01*
X1678505Y1634125D01*
X1678195Y1635583D01*
X1677420Y1636833D01*
X1676025Y1637667D01*
X1674165Y1638083D01*
X1673080Y1638917D01*
X1672615Y1640375D01*
X1672925Y1641833D01*
X1673700Y1642875D01*
X1674785Y1643500D01*
X1675870D01*
X1676955Y1643083D01*
X1677885Y1642042D01*
G01X1690750Y1631000D02*
X1684550D01*
Y1643500D01*
X1690750D01*
G01X1688270Y1637458D02*
X1684550D01*
G01X1715240Y1643500D02*
Y1631000D01*
G01Y1632875D02*
X1714620Y1631833D01*
X1713690Y1631208D01*
X1712605Y1631000D01*
X1711365Y1631417D01*
X1710435Y1632458D01*
X1709815Y1633708D01*
X1709660Y1635167D01*
X1709815Y1636625D01*
X1710435Y1637875D01*
X1711365Y1638917D01*
X1712605Y1639333D01*
X1713690Y1639125D01*
X1714465Y1638708D01*
X1715240Y1637875D01*
G01X1722680Y1631000D02*
Y1639333D01*
G01Y1637667D02*
X1723455Y1638500D01*
X1724230Y1639125D01*
X1725315Y1639333D01*
X1726090Y1639125D01*
X1727020Y1638500D01*
G01X1737250Y1639333D02*
Y1631000D01*
G01Y1642666D02*
X1736940Y1642875D01*
Y1643292D01*
X1737250Y1643500D01*
X1737560Y1643292D01*
Y1642875D01*
X1737250Y1642666D01*
G01X1749650Y1631000D02*
Y1643500D01*
G01X1762050Y1631000D02*
Y1643500D01*
G01X1789640D02*
Y1631000D01*
G01Y1632875D02*
X1789020Y1631833D01*
X1788090Y1631208D01*
X1787005Y1631000D01*
X1785765Y1631417D01*
X1784835Y1632458D01*
X1784215Y1633708D01*
X1784060Y1635167D01*
X1784215Y1636625D01*
X1784835Y1637875D01*
X1785765Y1638917D01*
X1787005Y1639333D01*
X1788090Y1639125D01*
X1788865Y1638708D01*
X1789640Y1637875D01*
G01X1799250Y1639333D02*
Y1631000D01*
G01Y1642666D02*
X1798940Y1642875D01*
Y1643292D01*
X1799250Y1643500D01*
X1799560Y1643292D01*
Y1642875D01*
X1799250Y1642666D01*
G01X1809480Y1631000D02*
Y1639333D01*
G01Y1637667D02*
X1810255Y1638500D01*
X1811030Y1639125D01*
X1812115Y1639333D01*
X1812890Y1639125D01*
X1813820Y1638500D01*
G01X1821725Y1636625D02*
X1826685D01*
X1826220Y1638083D01*
X1825445Y1638917D01*
X1824360Y1639333D01*
X1823275Y1639125D01*
X1822345Y1638500D01*
X1821725Y1637042D01*
X1821415Y1635791D01*
Y1634542D01*
X1821725Y1633292D01*
X1822500Y1632041D01*
X1823430Y1631208D01*
X1824515Y1631000D01*
X1825600Y1631417D01*
X1826685Y1632666D01*
G01X1838930Y1638292D02*
X1837845Y1639125D01*
X1836915Y1639333D01*
X1835675Y1638917D01*
X1834745Y1638083D01*
X1834125Y1636625D01*
X1833970Y1635167D01*
X1834125Y1633708D01*
X1834745Y1632458D01*
X1835675Y1631417D01*
X1836915Y1631000D01*
X1838000Y1631417D01*
X1838930Y1632250D01*
G01X1848850Y1643500D02*
Y1631000D01*
G01X1846680Y1639333D02*
X1851020D01*
G01X1861250D02*
Y1631000D01*
G01Y1642666D02*
X1860940Y1642875D01*
Y1643292D01*
X1861250Y1643500D01*
X1861560Y1643292D01*
Y1642875D01*
X1861250Y1642666D01*
G01X1873650Y1631000D02*
X1872720Y1631208D01*
X1871790Y1632041D01*
X1871170Y1633500D01*
X1870860Y1635167D01*
X1871170Y1636833D01*
X1871790Y1638292D01*
X1872720Y1639125D01*
X1873650Y1639333D01*
X1874580Y1639125D01*
X1875510Y1638292D01*
X1876130Y1636833D01*
X1876285Y1635167D01*
X1876130Y1633500D01*
X1875510Y1632041D01*
X1874580Y1631208D01*
X1873650Y1631000D01*
G01X1883415D02*
Y1639333D01*
G01Y1637250D02*
X1884035Y1638292D01*
X1884965Y1639125D01*
X1886205Y1639333D01*
X1887290Y1639125D01*
X1888220Y1638292D01*
X1888685Y1636833D01*
Y1631000D01*
G01X1236600Y1661000D02*
Y1995100D01*
X1720200D01*
Y1661000D01*
X1236600D01*
G01Y1717200D02*
X1720200D01*
G01X1236600Y1689100D02*
X1720200D01*
G01X1236600Y1801500D02*
X1720200D01*
G01X1236600Y1773400D02*
X1720200D01*
G01X1236600Y1745300D02*
X1720200D01*
G01X1236600Y1885800D02*
X1720200D01*
G01X1236600Y1857700D02*
X1720200D01*
G01X1236600Y1829600D02*
X1720200D01*
G01X1247605Y1923250D02*
Y1935750D01*
X1253495D01*
G01X1251325Y1929708D02*
X1247605D01*
G01X1261090Y1935750D02*
X1264810D01*
G01X1262950D02*
Y1923250D01*
G01X1261090D02*
X1264810D01*
G01X1276280Y1929500D02*
X1279380D01*
Y1925750D01*
X1278450Y1924500D01*
X1277365Y1923667D01*
X1275815Y1923250D01*
X1274265Y1923667D01*
X1273180Y1924500D01*
X1272250Y1925750D01*
X1271630Y1927208D01*
X1271320Y1928875D01*
Y1930333D01*
X1271630Y1931583D01*
X1272250Y1933042D01*
X1273180Y1934292D01*
X1274110Y1935125D01*
X1275350Y1935750D01*
X1276435D01*
X1277675Y1935333D01*
X1278605Y1934500D01*
G01X1284340Y1935750D02*
Y1926792D01*
X1284960Y1924916D01*
X1286200Y1923667D01*
X1287750Y1923250D01*
X1289300Y1923667D01*
X1290540Y1924916D01*
X1291160Y1926792D01*
Y1935750D01*
G01X1297050Y1923250D02*
Y1935750D01*
X1300925D01*
X1302165Y1935125D01*
X1302940Y1934292D01*
X1303250Y1932625D01*
X1302940Y1930958D01*
X1302010Y1929917D01*
X1300925Y1929292D01*
X1297050D01*
G01X1300925D02*
X1303250Y1923250D01*
G01X1315650D02*
X1309450D01*
Y1935750D01*
X1315650D01*
G01X1313170Y1929708D02*
X1309450D01*
G01X1236600Y1970100D02*
X1720200D01*
G01X1236600Y1942000D02*
X1720200D01*
G01X1236600Y1913900D02*
X1720200D01*
G01X1326500Y1942000D02*
Y1661000D01*
G01X1319990Y1976350D02*
Y1988850D01*
X1323090D01*
X1324330Y1988225D01*
X1325260Y1987392D01*
X1326035Y1986142D01*
X1326655Y1984683D01*
X1326810Y1982600D01*
X1326655Y1980517D01*
X1326035Y1979058D01*
X1325260Y1977808D01*
X1324330Y1976975D01*
X1323090Y1976350D01*
X1319990D01*
G01X1332700D02*
Y1988850D01*
X1336575D01*
X1337815Y1988225D01*
X1338590Y1987392D01*
X1338900Y1985725D01*
X1338590Y1984058D01*
X1337660Y1983017D01*
X1336575Y1982392D01*
X1332700D01*
G01X1336575D02*
X1338900Y1976350D01*
G01X1346340Y1988850D02*
X1350060D01*
G01X1348200D02*
Y1976350D01*
G01X1346340D02*
X1350060D01*
G01X1357500Y1988850D02*
Y1976350D01*
X1363700D01*
G01X1369900Y1988850D02*
Y1976350D01*
X1376100D01*
G01X1401210Y1987808D02*
X1400280Y1988433D01*
X1399195Y1988850D01*
X1397955D01*
X1396560Y1988225D01*
X1395475Y1987183D01*
X1394700Y1985933D01*
X1394080Y1983850D01*
X1393925Y1981975D01*
X1394235Y1980100D01*
X1394700Y1978850D01*
X1395630Y1977600D01*
X1396715Y1976767D01*
X1397800Y1976350D01*
X1398885D01*
X1399970Y1976767D01*
X1400900Y1977391D01*
X1401675Y1978225D01*
G01X1406945Y1976350D02*
Y1988850D01*
G01X1413455D02*
Y1976350D01*
G01Y1982600D02*
X1406945D01*
G01X1418725Y1976350D02*
X1422600Y1988850D01*
X1426475Y1976350D01*
G01X1425080Y1980725D02*
X1420120D01*
G01X1431900Y1976350D02*
Y1988850D01*
X1435775D01*
X1437015Y1988225D01*
X1437790Y1987392D01*
X1438100Y1985725D01*
X1437790Y1984058D01*
X1436860Y1983017D01*
X1435775Y1982392D01*
X1431900D01*
G01X1435775D02*
X1438100Y1976350D01*
G01X1447400Y1988850D02*
Y1976350D01*
G01X1443835Y1988850D02*
X1450965D01*
G01X1459800Y1975933D02*
X1459490Y1976142D01*
Y1976558D01*
X1459800Y1976767D01*
X1460110Y1976558D01*
Y1976142D01*
X1459800Y1975933D01*
G01Y1981558D02*
X1459490Y1981767D01*
Y1982183D01*
X1459800Y1982392D01*
X1460110Y1982183D01*
Y1981767D01*
X1459800Y1981558D01*
G01X1484600Y1988850D02*
Y1976350D01*
G01X1481035Y1988850D02*
X1488165D01*
G01X1497000Y1976350D02*
X1495760Y1976558D01*
X1494675Y1977391D01*
X1493745Y1978642D01*
X1493125Y1980100D01*
X1492815Y1981767D01*
Y1983433D01*
X1493125Y1985100D01*
X1493745Y1986558D01*
X1494675Y1987808D01*
X1495760Y1988642D01*
X1497000Y1988850D01*
X1498240Y1988642D01*
X1499325Y1987808D01*
X1500255Y1986558D01*
X1500875Y1985100D01*
X1501185Y1983433D01*
Y1981767D01*
X1500875Y1980100D01*
X1500255Y1978642D01*
X1499325Y1977391D01*
X1498240Y1976558D01*
X1497000Y1976350D01*
G01X1506300D02*
Y1988850D01*
X1510020D01*
X1511260Y1988225D01*
X1512190Y1986767D01*
X1512500Y1985100D01*
X1512190Y1983433D01*
X1511415Y1982183D01*
X1510020Y1981558D01*
X1506300D01*
G01X1534200Y1988850D02*
Y1976350D01*
G01X1532030Y1984683D02*
X1536370D01*
G01X1546600Y1976350D02*
X1545670Y1976558D01*
X1544740Y1977391D01*
X1544120Y1978850D01*
X1543810Y1980517D01*
X1544120Y1982183D01*
X1544740Y1983642D01*
X1545670Y1984475D01*
X1546600Y1984683D01*
X1547530Y1984475D01*
X1548460Y1983642D01*
X1549080Y1982183D01*
X1549235Y1980517D01*
X1549080Y1978850D01*
X1548460Y1977391D01*
X1547530Y1976558D01*
X1546600Y1976350D01*
G01X1572640Y1983017D02*
X1573260Y1983642D01*
X1573725Y1984683D01*
X1574035Y1986142D01*
X1573725Y1987392D01*
X1573105Y1988225D01*
X1572020Y1988850D01*
X1567835D01*
Y1976350D01*
X1572950D01*
X1574035Y1977183D01*
X1574655Y1978433D01*
X1574965Y1979892D01*
X1574655Y1981350D01*
X1573725Y1982600D01*
X1572640Y1983017D01*
X1567835D01*
G01X1583800Y1976350D02*
X1582560Y1976558D01*
X1581475Y1977391D01*
X1580545Y1978642D01*
X1579925Y1980100D01*
X1579615Y1981767D01*
Y1983433D01*
X1579925Y1985100D01*
X1580545Y1986558D01*
X1581475Y1987808D01*
X1582560Y1988642D01*
X1583800Y1988850D01*
X1585040Y1988642D01*
X1586125Y1987808D01*
X1587055Y1986558D01*
X1587675Y1985100D01*
X1587985Y1983433D01*
Y1981767D01*
X1587675Y1980100D01*
X1587055Y1978642D01*
X1586125Y1977391D01*
X1585040Y1976558D01*
X1583800Y1976350D01*
G01X1596200Y1988850D02*
Y1976350D01*
G01X1592635Y1988850D02*
X1599765D01*
G01X1608600D02*
Y1976350D01*
G01X1605035Y1988850D02*
X1612165D01*
G01X1621000Y1976350D02*
X1619760Y1976558D01*
X1618675Y1977391D01*
X1617745Y1978642D01*
X1617125Y1980100D01*
X1616815Y1981767D01*
Y1983433D01*
X1617125Y1985100D01*
X1617745Y1986558D01*
X1618675Y1987808D01*
X1619760Y1988642D01*
X1621000Y1988850D01*
X1622240Y1988642D01*
X1623325Y1987808D01*
X1624255Y1986558D01*
X1624875Y1985100D01*
X1625185Y1983433D01*
Y1981767D01*
X1624875Y1980100D01*
X1624255Y1978642D01*
X1623325Y1977391D01*
X1622240Y1976558D01*
X1621000Y1976350D01*
G01X1629370D02*
Y1988850D01*
X1633400Y1978433D01*
X1637430Y1988850D01*
Y1976350D01*
G01X1399815Y1726458D02*
X1400900Y1725417D01*
X1402140Y1725000D01*
X1403380Y1725417D01*
X1404465Y1726666D01*
X1405240Y1728542D01*
X1405550Y1730417D01*
Y1732708D01*
X1405240Y1734583D01*
X1404465Y1736250D01*
X1403535Y1737083D01*
X1402450Y1737500D01*
X1401210Y1737083D01*
X1400280Y1736250D01*
X1399660Y1735000D01*
X1399350Y1733333D01*
X1399660Y1731875D01*
X1400435Y1730417D01*
X1401365Y1729583D01*
X1402450Y1729375D01*
X1403690Y1729791D01*
X1404620Y1730833D01*
X1405550Y1732708D01*
G01X1414850Y1725000D02*
Y1737500D01*
X1412990Y1735000D01*
G01Y1725000D02*
X1416710D01*
G01X1427250Y1724583D02*
X1426940Y1724792D01*
Y1725208D01*
X1427250Y1725417D01*
X1427560Y1725208D01*
Y1724792D01*
X1427250Y1724583D01*
G01X1439650Y1737500D02*
X1438410Y1737083D01*
X1437480Y1736042D01*
X1436860Y1734792D01*
X1436395Y1733125D01*
X1436240Y1731250D01*
X1436395Y1729375D01*
X1436860Y1727708D01*
X1437480Y1726458D01*
X1438410Y1725417D01*
X1439650Y1725000D01*
X1440890Y1725417D01*
X1441820Y1726458D01*
X1442440Y1727708D01*
X1442905Y1729375D01*
X1443060Y1731250D01*
X1442905Y1733125D01*
X1442440Y1734792D01*
X1441820Y1736042D01*
X1440890Y1737083D01*
X1439650Y1737500D01*
G01X1396250Y1696900D02*
Y1709400D01*
X1394390Y1706900D01*
G01Y1696900D02*
X1398110D01*
G01X1410510D02*
Y1709400D01*
X1404775Y1700442D01*
X1412525D01*
G01X1418105Y1702108D02*
X1419190Y1703567D01*
X1420120Y1704400D01*
X1421360Y1704817D01*
X1422445Y1704400D01*
X1423220Y1703567D01*
X1423840Y1702317D01*
X1423995Y1700858D01*
X1423840Y1699608D01*
X1423220Y1698358D01*
X1422290Y1697317D01*
X1421205Y1696900D01*
X1419965Y1697317D01*
X1418880Y1698566D01*
X1418260Y1700442D01*
X1418105Y1702525D01*
X1418415Y1705233D01*
X1418880Y1706692D01*
X1419655Y1708150D01*
X1420740Y1709192D01*
X1421825Y1709400D01*
X1422910Y1708983D01*
X1423685Y1707942D01*
G01X1433450Y1696483D02*
X1433140Y1696692D01*
Y1697108D01*
X1433450Y1697317D01*
X1433760Y1697108D01*
Y1696692D01*
X1433450Y1696483D01*
G01X1445850Y1709400D02*
X1444610Y1708983D01*
X1443680Y1707942D01*
X1443060Y1706692D01*
X1442595Y1705025D01*
X1442440Y1703150D01*
X1442595Y1701275D01*
X1443060Y1699608D01*
X1443680Y1698358D01*
X1444610Y1697317D01*
X1445850Y1696900D01*
X1447090Y1697317D01*
X1448020Y1698358D01*
X1448640Y1699608D01*
X1449105Y1701275D01*
X1449260Y1703150D01*
X1449105Y1705025D01*
X1448640Y1706692D01*
X1448020Y1707942D01*
X1447090Y1708983D01*
X1445850Y1709400D01*
G01X1371140Y1668800D02*
X1371450Y1671508D01*
X1371915Y1673800D01*
X1372535Y1675883D01*
X1373310Y1678175D01*
X1374550Y1681300D01*
X1368350D01*
G01X1380440Y1670675D02*
X1381370Y1669633D01*
X1382455Y1669008D01*
X1383850Y1668800D01*
X1385245Y1669217D01*
X1386330Y1670050D01*
X1387105Y1671508D01*
X1387260Y1673175D01*
X1386950Y1674842D01*
X1386175Y1675883D01*
X1385090Y1676717D01*
X1384005Y1676925D01*
X1382920Y1676717D01*
X1381525Y1675883D01*
X1381990Y1681300D01*
X1386175D01*
G01X1396250Y1668383D02*
X1395940Y1668592D01*
Y1669008D01*
X1396250Y1669217D01*
X1396560Y1669008D01*
Y1668592D01*
X1396250Y1668383D01*
G01X1408650Y1681300D02*
X1407410Y1680883D01*
X1406480Y1679842D01*
X1405860Y1678592D01*
X1405395Y1676925D01*
X1405240Y1675050D01*
X1405395Y1673175D01*
X1405860Y1671508D01*
X1406480Y1670258D01*
X1407410Y1669217D01*
X1408650Y1668800D01*
X1409890Y1669217D01*
X1410820Y1670258D01*
X1411440Y1671508D01*
X1411905Y1673175D01*
X1412060Y1675050D01*
X1411905Y1676925D01*
X1411440Y1678592D01*
X1410820Y1679842D01*
X1409890Y1680883D01*
X1408650Y1681300D01*
G01X1418725Y1677133D02*
X1423375Y1668800D01*
G01Y1677133D02*
X1418725Y1668800D01*
G01X1430040Y1671300D02*
X1430970Y1669841D01*
X1432210Y1669008D01*
X1433605Y1668800D01*
X1434845Y1669008D01*
X1436085Y1670050D01*
X1436860Y1671300D01*
X1437015Y1672550D01*
X1436705Y1674008D01*
X1435620Y1675050D01*
X1434535Y1675467D01*
X1433140D01*
G01X1434535D02*
X1435465Y1676092D01*
X1436240Y1677133D01*
X1436550Y1678383D01*
X1436240Y1679633D01*
X1435465Y1680675D01*
X1434070Y1681300D01*
X1432675Y1681092D01*
X1431280Y1680258D01*
G01X1442905Y1679217D02*
X1443835Y1680466D01*
X1444920Y1681092D01*
X1446160Y1681300D01*
X1447710Y1680883D01*
X1448795Y1679842D01*
X1449105Y1678592D01*
X1448950Y1677341D01*
X1448330Y1676300D01*
X1445230Y1674217D01*
X1443835Y1672758D01*
X1442905Y1670675D01*
X1442595Y1668800D01*
X1449105D01*
G01X1458250Y1668383D02*
X1457940Y1668592D01*
Y1669008D01*
X1458250Y1669217D01*
X1458560Y1669008D01*
Y1668592D01*
X1458250Y1668383D01*
G01X1470650Y1681300D02*
X1469410Y1680883D01*
X1468480Y1679842D01*
X1467860Y1678592D01*
X1467395Y1676925D01*
X1467240Y1675050D01*
X1467395Y1673175D01*
X1467860Y1671508D01*
X1468480Y1670258D01*
X1469410Y1669217D01*
X1470650Y1668800D01*
X1471890Y1669217D01*
X1472820Y1670258D01*
X1473440Y1671508D01*
X1473905Y1673175D01*
X1474060Y1675050D01*
X1473905Y1676925D01*
X1473440Y1678592D01*
X1472820Y1679842D01*
X1471890Y1680883D01*
X1470650Y1681300D01*
G01X1402140Y1781200D02*
X1402450Y1783908D01*
X1402915Y1786200D01*
X1403535Y1788283D01*
X1404310Y1790575D01*
X1405550Y1793700D01*
X1399350D01*
G01X1411440Y1783700D02*
X1412370Y1782241D01*
X1413610Y1781408D01*
X1415005Y1781200D01*
X1416245Y1781408D01*
X1417485Y1782450D01*
X1418260Y1783700D01*
X1418415Y1784950D01*
X1418105Y1786408D01*
X1417020Y1787450D01*
X1415935Y1787867D01*
X1414540D01*
G01X1415935D02*
X1416865Y1788492D01*
X1417640Y1789533D01*
X1417950Y1790783D01*
X1417640Y1792033D01*
X1416865Y1793075D01*
X1415470Y1793700D01*
X1414075Y1793492D01*
X1412680Y1792658D01*
G01X1427250Y1780783D02*
X1426940Y1780992D01*
Y1781408D01*
X1427250Y1781617D01*
X1427560Y1781408D01*
Y1780992D01*
X1427250Y1780783D01*
G01X1439650Y1793700D02*
X1438410Y1793283D01*
X1437480Y1792242D01*
X1436860Y1790992D01*
X1436395Y1789325D01*
X1436240Y1787450D01*
X1436395Y1785575D01*
X1436860Y1783908D01*
X1437480Y1782658D01*
X1438410Y1781617D01*
X1439650Y1781200D01*
X1440890Y1781617D01*
X1441820Y1782658D01*
X1442440Y1783908D01*
X1442905Y1785575D01*
X1443060Y1787450D01*
X1442905Y1789325D01*
X1442440Y1790992D01*
X1441820Y1792242D01*
X1440890Y1793283D01*
X1439650Y1793700D01*
G01X1402450Y1753100D02*
X1403535Y1753308D01*
X1404775Y1753933D01*
X1405550Y1754975D01*
X1405860Y1756433D01*
X1405550Y1757891D01*
X1404620Y1759142D01*
X1403225Y1759767D01*
X1401675D01*
X1400745Y1760183D01*
X1399970Y1761225D01*
X1399660Y1762683D01*
X1400125Y1764142D01*
X1401210Y1765183D01*
X1402450Y1765600D01*
X1403690Y1765183D01*
X1404775Y1764142D01*
X1405240Y1762683D01*
X1404930Y1761225D01*
X1404155Y1760183D01*
X1403225Y1759767D01*
X1401675D01*
X1400280Y1759142D01*
X1399350Y1757891D01*
X1399040Y1756433D01*
X1399350Y1754975D01*
X1400125Y1753933D01*
X1401365Y1753308D01*
X1402450Y1753100D01*
G01X1411905Y1758308D02*
X1412990Y1759767D01*
X1413920Y1760600D01*
X1415160Y1761017D01*
X1416245Y1760600D01*
X1417020Y1759767D01*
X1417640Y1758517D01*
X1417795Y1757058D01*
X1417640Y1755808D01*
X1417020Y1754558D01*
X1416090Y1753517D01*
X1415005Y1753100D01*
X1413765Y1753517D01*
X1412680Y1754766D01*
X1412060Y1756642D01*
X1411905Y1758725D01*
X1412215Y1761433D01*
X1412680Y1762892D01*
X1413455Y1764350D01*
X1414540Y1765392D01*
X1415625Y1765600D01*
X1416710Y1765183D01*
X1417485Y1764142D01*
G01X1427250Y1752683D02*
X1426940Y1752892D01*
Y1753308D01*
X1427250Y1753517D01*
X1427560Y1753308D01*
Y1752892D01*
X1427250Y1752683D01*
G01X1439650Y1765600D02*
X1438410Y1765183D01*
X1437480Y1764142D01*
X1436860Y1762892D01*
X1436395Y1761225D01*
X1436240Y1759350D01*
X1436395Y1757475D01*
X1436860Y1755808D01*
X1437480Y1754558D01*
X1438410Y1753517D01*
X1439650Y1753100D01*
X1440890Y1753517D01*
X1441820Y1754558D01*
X1442440Y1755808D01*
X1442905Y1757475D01*
X1443060Y1759350D01*
X1442905Y1761225D01*
X1442440Y1762892D01*
X1441820Y1764142D01*
X1440890Y1765183D01*
X1439650Y1765600D01*
G01X1402450Y1865500D02*
Y1878000D01*
X1400590Y1875500D01*
G01Y1865500D02*
X1404310D01*
G01X1411905Y1870708D02*
X1412990Y1872167D01*
X1413920Y1873000D01*
X1415160Y1873417D01*
X1416245Y1873000D01*
X1417020Y1872167D01*
X1417640Y1870917D01*
X1417795Y1869458D01*
X1417640Y1868208D01*
X1417020Y1866958D01*
X1416090Y1865917D01*
X1415005Y1865500D01*
X1413765Y1865917D01*
X1412680Y1867166D01*
X1412060Y1869042D01*
X1411905Y1871125D01*
X1412215Y1873833D01*
X1412680Y1875292D01*
X1413455Y1876750D01*
X1414540Y1877792D01*
X1415625Y1878000D01*
X1416710Y1877583D01*
X1417485Y1876542D01*
G01X1427250Y1865083D02*
X1426940Y1865292D01*
Y1865708D01*
X1427250Y1865917D01*
X1427560Y1865708D01*
Y1865292D01*
X1427250Y1865083D01*
G01X1439650Y1878000D02*
X1438410Y1877583D01*
X1437480Y1876542D01*
X1436860Y1875292D01*
X1436395Y1873625D01*
X1436240Y1871750D01*
X1436395Y1869875D01*
X1436860Y1868208D01*
X1437480Y1866958D01*
X1438410Y1865917D01*
X1439650Y1865500D01*
X1440890Y1865917D01*
X1441820Y1866958D01*
X1442440Y1868208D01*
X1442905Y1869875D01*
X1443060Y1871750D01*
X1442905Y1873625D01*
X1442440Y1875292D01*
X1441820Y1876542D01*
X1440890Y1877583D01*
X1439650Y1878000D01*
G01X1396250Y1837400D02*
Y1849900D01*
X1394390Y1847400D01*
G01Y1837400D02*
X1398110D01*
G01X1410510D02*
Y1849900D01*
X1404775Y1840942D01*
X1412525D01*
G01X1421050Y1849900D02*
X1419810Y1849483D01*
X1418880Y1848442D01*
X1418260Y1847192D01*
X1417795Y1845525D01*
X1417640Y1843650D01*
X1417795Y1841775D01*
X1418260Y1840108D01*
X1418880Y1838858D01*
X1419810Y1837817D01*
X1421050Y1837400D01*
X1422290Y1837817D01*
X1423220Y1838858D01*
X1423840Y1840108D01*
X1424305Y1841775D01*
X1424460Y1843650D01*
X1424305Y1845525D01*
X1423840Y1847192D01*
X1423220Y1848442D01*
X1422290Y1849483D01*
X1421050Y1849900D01*
G01X1433450Y1836983D02*
X1433140Y1837192D01*
Y1837608D01*
X1433450Y1837817D01*
X1433760Y1837608D01*
Y1837192D01*
X1433450Y1836983D01*
G01X1445850Y1849900D02*
X1444610Y1849483D01*
X1443680Y1848442D01*
X1443060Y1847192D01*
X1442595Y1845525D01*
X1442440Y1843650D01*
X1442595Y1841775D01*
X1443060Y1840108D01*
X1443680Y1838858D01*
X1444610Y1837817D01*
X1445850Y1837400D01*
X1447090Y1837817D01*
X1448020Y1838858D01*
X1448640Y1840108D01*
X1449105Y1841775D01*
X1449260Y1843650D01*
X1449105Y1845525D01*
X1448640Y1847192D01*
X1448020Y1848442D01*
X1447090Y1849483D01*
X1445850Y1849900D01*
G01X1396250Y1809300D02*
Y1821800D01*
X1394390Y1819300D01*
G01Y1809300D02*
X1398110D01*
G01X1405240Y1811175D02*
X1406170Y1810133D01*
X1407255Y1809508D01*
X1408650Y1809300D01*
X1410045Y1809717D01*
X1411130Y1810550D01*
X1411905Y1812008D01*
X1412060Y1813675D01*
X1411750Y1815342D01*
X1410975Y1816383D01*
X1409890Y1817217D01*
X1408805Y1817425D01*
X1407720Y1817217D01*
X1406325Y1816383D01*
X1406790Y1821800D01*
X1410975D01*
G01X1420740Y1809300D02*
X1421050Y1812008D01*
X1421515Y1814300D01*
X1422135Y1816383D01*
X1422910Y1818675D01*
X1424150Y1821800D01*
X1417950D01*
G01X1433450Y1808883D02*
X1433140Y1809092D01*
Y1809508D01*
X1433450Y1809717D01*
X1433760Y1809508D01*
Y1809092D01*
X1433450Y1808883D01*
G01X1445850Y1821800D02*
X1444610Y1821383D01*
X1443680Y1820342D01*
X1443060Y1819092D01*
X1442595Y1817425D01*
X1442440Y1815550D01*
X1442595Y1813675D01*
X1443060Y1812008D01*
X1443680Y1810758D01*
X1444610Y1809717D01*
X1445850Y1809300D01*
X1447090Y1809717D01*
X1448020Y1810758D01*
X1448640Y1812008D01*
X1449105Y1813675D01*
X1449260Y1815550D01*
X1449105Y1817425D01*
X1448640Y1819092D01*
X1448020Y1820342D01*
X1447090Y1821383D01*
X1445850Y1821800D01*
G01X1350525Y1951350D02*
X1354400Y1963850D01*
X1358275Y1951350D01*
G01X1356880Y1955725D02*
X1351920D01*
G01X1363700Y1963850D02*
Y1951350D01*
X1369900D01*
G01X1376100Y1963850D02*
Y1951350D01*
X1382300D01*
G01X1400590Y1963850D02*
Y1954892D01*
X1401210Y1953016D01*
X1402450Y1951767D01*
X1404000Y1951350D01*
X1405550Y1951767D01*
X1406790Y1953016D01*
X1407410Y1954892D01*
Y1963850D01*
G01X1412835Y1951350D02*
Y1963850D01*
X1419965Y1951350D01*
Y1963850D01*
G01X1426940D02*
X1430660D01*
G01X1428800D02*
Y1951350D01*
G01X1426940D02*
X1430660D01*
G01X1441200Y1963850D02*
Y1951350D01*
G01X1437635Y1963850D02*
X1444765D01*
G01X1450345Y1953016D02*
X1451585Y1951975D01*
X1452980Y1951350D01*
X1454220D01*
X1455460Y1951975D01*
X1456390Y1953016D01*
X1456855Y1954475D01*
X1456545Y1955933D01*
X1455770Y1957183D01*
X1454375Y1958017D01*
X1452515Y1958433D01*
X1451430Y1959267D01*
X1450965Y1960725D01*
X1451275Y1962183D01*
X1452050Y1963225D01*
X1453135Y1963850D01*
X1454220D01*
X1455305Y1963433D01*
X1456235Y1962392D01*
G01X1474525Y1951350D02*
X1478400Y1963850D01*
X1482275Y1951350D01*
G01X1480880Y1955725D02*
X1475920D01*
G01X1487700Y1951350D02*
Y1963850D01*
X1491575D01*
X1492815Y1963225D01*
X1493590Y1962392D01*
X1493900Y1960725D01*
X1493590Y1959058D01*
X1492660Y1958017D01*
X1491575Y1957392D01*
X1487700D01*
G01X1491575D02*
X1493900Y1951350D01*
G01X1506300D02*
X1500100D01*
Y1963850D01*
X1506300D01*
G01X1503820Y1957808D02*
X1500100D01*
G01X1526140Y1963850D02*
X1529860D01*
G01X1528000D02*
Y1951350D01*
G01X1526140D02*
X1529860D01*
G01X1536835D02*
Y1963850D01*
X1543965Y1951350D01*
Y1963850D01*
G01X1561170Y1951350D02*
Y1963850D01*
X1565200Y1953433D01*
X1569230Y1963850D01*
Y1951350D01*
G01X1575740Y1963850D02*
X1579460D01*
G01X1577600D02*
Y1951350D01*
G01X1575740D02*
X1579460D01*
G01X1586900Y1963850D02*
Y1951350D01*
X1593100D01*
G01X1599145Y1953016D02*
X1600385Y1951975D01*
X1601780Y1951350D01*
X1603020D01*
X1604260Y1951975D01*
X1605190Y1953016D01*
X1605655Y1954475D01*
X1605345Y1955933D01*
X1604570Y1957183D01*
X1603175Y1958017D01*
X1601315Y1958433D01*
X1600230Y1959267D01*
X1599765Y1960725D01*
X1600075Y1962183D01*
X1600850Y1963225D01*
X1601935Y1963850D01*
X1603020D01*
X1604105Y1963433D01*
X1605035Y1962392D01*
G01X1399195Y1924916D02*
X1400435Y1923875D01*
X1401830Y1923250D01*
X1403070D01*
X1404310Y1923875D01*
X1405240Y1924916D01*
X1405705Y1926375D01*
X1405395Y1927833D01*
X1404620Y1929083D01*
X1403225Y1929917D01*
X1401365Y1930333D01*
X1400280Y1931167D01*
X1399815Y1932625D01*
X1400125Y1934083D01*
X1400900Y1935125D01*
X1401985Y1935750D01*
X1403070D01*
X1404155Y1935333D01*
X1405085Y1934292D01*
G01X1412990Y1935750D02*
X1416710D01*
G01X1414850D02*
Y1923250D01*
G01X1412990D02*
X1416710D01*
G01X1424305Y1935750D02*
X1430195D01*
X1424305Y1923250D01*
X1430195D01*
G01X1442750D02*
X1436550D01*
Y1935750D01*
X1442750D01*
G01X1440270Y1929708D02*
X1436550D01*
G01X1402450Y1893600D02*
Y1906100D01*
X1400590Y1903600D01*
G01Y1893600D02*
X1404310D01*
G01X1411905Y1904017D02*
X1412835Y1905266D01*
X1413920Y1905892D01*
X1415160Y1906100D01*
X1416710Y1905683D01*
X1417795Y1904642D01*
X1418105Y1903392D01*
X1417950Y1902141D01*
X1417330Y1901100D01*
X1414230Y1899017D01*
X1412835Y1897558D01*
X1411905Y1895475D01*
X1411595Y1893600D01*
X1418105D01*
G01X1427250Y1893183D02*
X1426940Y1893392D01*
Y1893808D01*
X1427250Y1894017D01*
X1427560Y1893808D01*
Y1893392D01*
X1427250Y1893183D01*
G01X1439650Y1906100D02*
X1438410Y1905683D01*
X1437480Y1904642D01*
X1436860Y1903392D01*
X1436395Y1901725D01*
X1436240Y1899850D01*
X1436395Y1897975D01*
X1436860Y1896308D01*
X1437480Y1895058D01*
X1438410Y1894017D01*
X1439650Y1893600D01*
X1440890Y1894017D01*
X1441820Y1895058D01*
X1442440Y1896308D01*
X1442905Y1897975D01*
X1443060Y1899850D01*
X1442905Y1901725D01*
X1442440Y1903392D01*
X1441820Y1904642D01*
X1440890Y1905683D01*
X1439650Y1906100D01*
G01X1519785Y1725000D02*
Y1737500D01*
X1526915Y1725000D01*
Y1737500D01*
G01X1535750Y1725000D02*
X1534510Y1725208D01*
X1533425Y1726041D01*
X1532495Y1727292D01*
X1531875Y1728750D01*
X1531565Y1730417D01*
Y1732083D01*
X1531875Y1733750D01*
X1532495Y1735208D01*
X1533425Y1736458D01*
X1534510Y1737292D01*
X1535750Y1737500D01*
X1536990Y1737292D01*
X1538075Y1736458D01*
X1539005Y1735208D01*
X1539625Y1733750D01*
X1539935Y1732083D01*
Y1730417D01*
X1539625Y1728750D01*
X1539005Y1727292D01*
X1538075Y1726041D01*
X1536990Y1725208D01*
X1535750Y1725000D01*
G01X1544585D02*
Y1737500D01*
X1551715Y1725000D01*
Y1737500D01*
G01X1558535Y1729167D02*
X1562565D01*
G01X1569850Y1725000D02*
Y1737500D01*
X1573570D01*
X1574810Y1736875D01*
X1575740Y1735417D01*
X1576050Y1733750D01*
X1575740Y1732083D01*
X1574965Y1730833D01*
X1573570Y1730208D01*
X1569850D01*
G01X1582250Y1737500D02*
Y1725000D01*
X1588450D01*
G01X1593875D02*
X1597750Y1737500D01*
X1601625Y1725000D01*
G01X1600230Y1729375D02*
X1595270D01*
G01X1610150Y1737500D02*
Y1725000D01*
G01X1606585Y1737500D02*
X1613715D01*
G01X1625650Y1725000D02*
X1619450D01*
Y1737500D01*
X1625650D01*
G01X1623170Y1731458D02*
X1619450D01*
G01X1631540Y1725000D02*
Y1737500D01*
X1634640D01*
X1635880Y1736875D01*
X1636810Y1736042D01*
X1637585Y1734792D01*
X1638205Y1733333D01*
X1638360Y1731250D01*
X1638205Y1729167D01*
X1637585Y1727708D01*
X1636810Y1726458D01*
X1635880Y1725625D01*
X1634640Y1725000D01*
X1631540D01*
G01X1519785Y1696900D02*
Y1709400D01*
X1526915Y1696900D01*
Y1709400D01*
G01X1535750Y1696900D02*
X1534510Y1697108D01*
X1533425Y1697941D01*
X1532495Y1699192D01*
X1531875Y1700650D01*
X1531565Y1702317D01*
Y1703983D01*
X1531875Y1705650D01*
X1532495Y1707108D01*
X1533425Y1708358D01*
X1534510Y1709192D01*
X1535750Y1709400D01*
X1536990Y1709192D01*
X1538075Y1708358D01*
X1539005Y1707108D01*
X1539625Y1705650D01*
X1539935Y1703983D01*
Y1702317D01*
X1539625Y1700650D01*
X1539005Y1699192D01*
X1538075Y1697941D01*
X1536990Y1697108D01*
X1535750Y1696900D01*
G01X1544585D02*
Y1709400D01*
X1551715Y1696900D01*
Y1709400D01*
G01X1558535Y1701067D02*
X1562565D01*
G01X1569850Y1696900D02*
Y1709400D01*
X1573570D01*
X1574810Y1708775D01*
X1575740Y1707317D01*
X1576050Y1705650D01*
X1575740Y1703983D01*
X1574965Y1702733D01*
X1573570Y1702108D01*
X1569850D01*
G01X1582250Y1709400D02*
Y1696900D01*
X1588450D01*
G01X1593875D02*
X1597750Y1709400D01*
X1601625Y1696900D01*
G01X1600230Y1701275D02*
X1595270D01*
G01X1610150Y1709400D02*
Y1696900D01*
G01X1606585Y1709400D02*
X1613715D01*
G01X1625650Y1696900D02*
X1619450D01*
Y1709400D01*
X1625650D01*
G01X1623170Y1703358D02*
X1619450D01*
G01X1631540Y1696900D02*
Y1709400D01*
X1634640D01*
X1635880Y1708775D01*
X1636810Y1707942D01*
X1637585Y1706692D01*
X1638205Y1705233D01*
X1638360Y1703150D01*
X1638205Y1701067D01*
X1637585Y1699608D01*
X1636810Y1698358D01*
X1635880Y1697525D01*
X1634640Y1696900D01*
X1631540D01*
G01X1545050Y1668800D02*
Y1681300D01*
X1548770D01*
X1550010Y1680675D01*
X1550940Y1679217D01*
X1551250Y1677550D01*
X1550940Y1675883D01*
X1550165Y1674633D01*
X1548770Y1674008D01*
X1545050D01*
G01X1557450Y1681300D02*
Y1668800D01*
X1563650D01*
G01X1569075D02*
X1572950Y1681300D01*
X1576825Y1668800D01*
G01X1575430Y1673175D02*
X1570470D01*
G01X1585350Y1681300D02*
Y1668800D01*
G01X1581785Y1681300D02*
X1588915D01*
G01X1600850Y1668800D02*
X1594650D01*
Y1681300D01*
X1600850D01*
G01X1598370Y1675258D02*
X1594650D01*
G01X1606740Y1668800D02*
Y1681300D01*
X1609840D01*
X1611080Y1680675D01*
X1612010Y1679842D01*
X1612785Y1678592D01*
X1613405Y1677133D01*
X1613560Y1675050D01*
X1613405Y1672967D01*
X1612785Y1671508D01*
X1612010Y1670258D01*
X1611080Y1669425D01*
X1609840Y1668800D01*
X1606740D01*
G01X1515600Y1942000D02*
Y1661000D01*
G01X1519785Y1781200D02*
Y1793700D01*
X1526915Y1781200D01*
Y1793700D01*
G01X1535750Y1781200D02*
X1534510Y1781408D01*
X1533425Y1782241D01*
X1532495Y1783492D01*
X1531875Y1784950D01*
X1531565Y1786617D01*
Y1788283D01*
X1531875Y1789950D01*
X1532495Y1791408D01*
X1533425Y1792658D01*
X1534510Y1793492D01*
X1535750Y1793700D01*
X1536990Y1793492D01*
X1538075Y1792658D01*
X1539005Y1791408D01*
X1539625Y1789950D01*
X1539935Y1788283D01*
Y1786617D01*
X1539625Y1784950D01*
X1539005Y1783492D01*
X1538075Y1782241D01*
X1536990Y1781408D01*
X1535750Y1781200D01*
G01X1544585D02*
Y1793700D01*
X1551715Y1781200D01*
Y1793700D01*
G01X1558535Y1785367D02*
X1562565D01*
G01X1569850Y1781200D02*
Y1793700D01*
X1573570D01*
X1574810Y1793075D01*
X1575740Y1791617D01*
X1576050Y1789950D01*
X1575740Y1788283D01*
X1574965Y1787033D01*
X1573570Y1786408D01*
X1569850D01*
G01X1582250Y1793700D02*
Y1781200D01*
X1588450D01*
G01X1593875D02*
X1597750Y1793700D01*
X1601625Y1781200D01*
G01X1600230Y1785575D02*
X1595270D01*
G01X1610150Y1793700D02*
Y1781200D01*
G01X1606585Y1793700D02*
X1613715D01*
G01X1625650Y1781200D02*
X1619450D01*
Y1793700D01*
X1625650D01*
G01X1623170Y1787658D02*
X1619450D01*
G01X1631540Y1781200D02*
Y1793700D01*
X1634640D01*
X1635880Y1793075D01*
X1636810Y1792242D01*
X1637585Y1790992D01*
X1638205Y1789533D01*
X1638360Y1787450D01*
X1638205Y1785367D01*
X1637585Y1783908D01*
X1636810Y1782658D01*
X1635880Y1781825D01*
X1634640Y1781200D01*
X1631540D01*
G01X1519785Y1753100D02*
Y1765600D01*
X1526915Y1753100D01*
Y1765600D01*
G01X1535750Y1753100D02*
X1534510Y1753308D01*
X1533425Y1754141D01*
X1532495Y1755392D01*
X1531875Y1756850D01*
X1531565Y1758517D01*
Y1760183D01*
X1531875Y1761850D01*
X1532495Y1763308D01*
X1533425Y1764558D01*
X1534510Y1765392D01*
X1535750Y1765600D01*
X1536990Y1765392D01*
X1538075Y1764558D01*
X1539005Y1763308D01*
X1539625Y1761850D01*
X1539935Y1760183D01*
Y1758517D01*
X1539625Y1756850D01*
X1539005Y1755392D01*
X1538075Y1754141D01*
X1536990Y1753308D01*
X1535750Y1753100D01*
G01X1544585D02*
Y1765600D01*
X1551715Y1753100D01*
Y1765600D01*
G01X1558535Y1757267D02*
X1562565D01*
G01X1569850Y1753100D02*
Y1765600D01*
X1573570D01*
X1574810Y1764975D01*
X1575740Y1763517D01*
X1576050Y1761850D01*
X1575740Y1760183D01*
X1574965Y1758933D01*
X1573570Y1758308D01*
X1569850D01*
G01X1582250Y1765600D02*
Y1753100D01*
X1588450D01*
G01X1593875D02*
X1597750Y1765600D01*
X1601625Y1753100D01*
G01X1600230Y1757475D02*
X1595270D01*
G01X1610150Y1765600D02*
Y1753100D01*
G01X1606585Y1765600D02*
X1613715D01*
G01X1625650Y1753100D02*
X1619450D01*
Y1765600D01*
X1625650D01*
G01X1623170Y1759558D02*
X1619450D01*
G01X1631540Y1753100D02*
Y1765600D01*
X1634640D01*
X1635880Y1764975D01*
X1636810Y1764142D01*
X1637585Y1762892D01*
X1638205Y1761433D01*
X1638360Y1759350D01*
X1638205Y1757267D01*
X1637585Y1755808D01*
X1636810Y1754558D01*
X1635880Y1753725D01*
X1634640Y1753100D01*
X1631540D01*
G01X1545050Y1865500D02*
Y1878000D01*
X1548770D01*
X1550010Y1877375D01*
X1550940Y1875917D01*
X1551250Y1874250D01*
X1550940Y1872583D01*
X1550165Y1871333D01*
X1548770Y1870708D01*
X1545050D01*
G01X1557450Y1878000D02*
Y1865500D01*
X1563650D01*
G01X1569075D02*
X1572950Y1878000D01*
X1576825Y1865500D01*
G01X1575430Y1869875D02*
X1570470D01*
G01X1585350Y1878000D02*
Y1865500D01*
G01X1581785Y1878000D02*
X1588915D01*
G01X1600850Y1865500D02*
X1594650D01*
Y1878000D01*
X1600850D01*
G01X1598370Y1871958D02*
X1594650D01*
G01X1606740Y1865500D02*
Y1878000D01*
X1609840D01*
X1611080Y1877375D01*
X1612010Y1876542D01*
X1612785Y1875292D01*
X1613405Y1873833D01*
X1613560Y1871750D01*
X1613405Y1869667D01*
X1612785Y1868208D01*
X1612010Y1866958D01*
X1611080Y1866125D01*
X1609840Y1865500D01*
X1606740D01*
G01X1545050Y1837400D02*
Y1849900D01*
X1548770D01*
X1550010Y1849275D01*
X1550940Y1847817D01*
X1551250Y1846150D01*
X1550940Y1844483D01*
X1550165Y1843233D01*
X1548770Y1842608D01*
X1545050D01*
G01X1557450Y1849900D02*
Y1837400D01*
X1563650D01*
G01X1569075D02*
X1572950Y1849900D01*
X1576825Y1837400D01*
G01X1575430Y1841775D02*
X1570470D01*
G01X1585350Y1849900D02*
Y1837400D01*
G01X1581785Y1849900D02*
X1588915D01*
G01X1600850Y1837400D02*
X1594650D01*
Y1849900D01*
X1600850D01*
G01X1598370Y1843858D02*
X1594650D01*
G01X1606740Y1837400D02*
Y1849900D01*
X1609840D01*
X1611080Y1849275D01*
X1612010Y1848442D01*
X1612785Y1847192D01*
X1613405Y1845733D01*
X1613560Y1843650D01*
X1613405Y1841567D01*
X1612785Y1840108D01*
X1612010Y1838858D01*
X1611080Y1838025D01*
X1609840Y1837400D01*
X1606740D01*
G01X1545050Y1809300D02*
Y1821800D01*
X1548770D01*
X1550010Y1821175D01*
X1550940Y1819717D01*
X1551250Y1818050D01*
X1550940Y1816383D01*
X1550165Y1815133D01*
X1548770Y1814508D01*
X1545050D01*
G01X1557450Y1821800D02*
Y1809300D01*
X1563650D01*
G01X1569075D02*
X1572950Y1821800D01*
X1576825Y1809300D01*
G01X1575430Y1813675D02*
X1570470D01*
G01X1585350Y1821800D02*
Y1809300D01*
G01X1581785Y1821800D02*
X1588915D01*
G01X1600850Y1809300D02*
X1594650D01*
Y1821800D01*
X1600850D01*
G01X1598370Y1815758D02*
X1594650D01*
G01X1606740Y1809300D02*
Y1821800D01*
X1609840D01*
X1611080Y1821175D01*
X1612010Y1820342D01*
X1612785Y1819092D01*
X1613405Y1817633D01*
X1613560Y1815550D01*
X1613405Y1813467D01*
X1612785Y1812008D01*
X1612010Y1810758D01*
X1611080Y1809925D01*
X1609840Y1809300D01*
X1606740D01*
G01X1545050Y1923250D02*
Y1935750D01*
X1548770D01*
X1550010Y1935125D01*
X1550940Y1933667D01*
X1551250Y1932000D01*
X1550940Y1930333D01*
X1550165Y1929083D01*
X1548770Y1928458D01*
X1545050D01*
G01X1557450Y1935750D02*
Y1923250D01*
X1563650D01*
G01X1569075D02*
X1572950Y1935750D01*
X1576825Y1923250D01*
G01X1575430Y1927625D02*
X1570470D01*
G01X1585350Y1935750D02*
Y1923250D01*
G01X1581785Y1935750D02*
X1588915D01*
G01X1600850Y1923250D02*
X1594650D01*
Y1935750D01*
X1600850D01*
G01X1598370Y1929708D02*
X1594650D01*
G01X1606740Y1923250D02*
Y1935750D01*
X1609840D01*
X1611080Y1935125D01*
X1612010Y1934292D01*
X1612785Y1933042D01*
X1613405Y1931583D01*
X1613560Y1929500D01*
X1613405Y1927417D01*
X1612785Y1925958D01*
X1612010Y1924708D01*
X1611080Y1923875D01*
X1609840Y1923250D01*
X1606740D01*
G01X1545050Y1893600D02*
Y1906100D01*
X1548770D01*
X1550010Y1905475D01*
X1550940Y1904017D01*
X1551250Y1902350D01*
X1550940Y1900683D01*
X1550165Y1899433D01*
X1548770Y1898808D01*
X1545050D01*
G01X1557450Y1906100D02*
Y1893600D01*
X1563650D01*
G01X1569075D02*
X1572950Y1906100D01*
X1576825Y1893600D01*
G01X1575430Y1897975D02*
X1570470D01*
G01X1585350Y1906100D02*
Y1893600D01*
G01X1581785Y1906100D02*
X1588915D01*
G01X1600850Y1893600D02*
X1594650D01*
Y1906100D01*
X1600850D01*
G01X1598370Y1900058D02*
X1594650D01*
G01X1606740Y1893600D02*
Y1906100D01*
X1609840D01*
X1611080Y1905475D01*
X1612010Y1904642D01*
X1612785Y1903392D01*
X1613405Y1901933D01*
X1613560Y1899850D01*
X1613405Y1897767D01*
X1612785Y1896308D01*
X1612010Y1895058D01*
X1611080Y1894225D01*
X1609840Y1893600D01*
X1606740D01*
G01X1642700Y1942000D02*
Y1661000D01*
G01X1664710Y1865500D02*
Y1878000D01*
X1658975Y1869042D01*
X1666725D01*
G01X1675250Y1865500D02*
Y1878000D01*
X1673390Y1875500D01*
G01Y1865500D02*
X1677110D01*
G01X1687340D02*
X1687650Y1868208D01*
X1688115Y1870500D01*
X1688735Y1872583D01*
X1689510Y1874875D01*
X1690750Y1878000D01*
X1684550D01*
G01X1697105Y1875917D02*
X1698035Y1877166D01*
X1699120Y1877792D01*
X1700360Y1878000D01*
X1701910Y1877583D01*
X1702995Y1876542D01*
X1703305Y1875292D01*
X1703150Y1874041D01*
X1702530Y1873000D01*
X1699430Y1870917D01*
X1698035Y1869458D01*
X1697105Y1867375D01*
X1696795Y1865500D01*
X1703305D01*
G01X1669050Y1923250D02*
X1667810Y1923458D01*
X1666725Y1924291D01*
X1665795Y1925542D01*
X1665175Y1927000D01*
X1664865Y1928667D01*
Y1930333D01*
X1665175Y1932000D01*
X1665795Y1933458D01*
X1666725Y1934708D01*
X1667810Y1935542D01*
X1669050Y1935750D01*
X1670290Y1935542D01*
X1671375Y1934708D01*
X1672305Y1933458D01*
X1672925Y1932000D01*
X1673235Y1930333D01*
Y1928667D01*
X1672925Y1927000D01*
X1672305Y1925542D01*
X1671375Y1924291D01*
X1670290Y1923458D01*
X1669050Y1923250D01*
G01X1670290Y1926583D02*
X1672150Y1923250D01*
G01X1681450Y1935750D02*
Y1923250D01*
G01X1677885Y1935750D02*
X1685015D01*
G01X1693850Y1923250D02*
Y1928875D01*
X1690750Y1935750D01*
G01X1696950D02*
X1693850Y1928875D01*
G01X1662850Y1893600D02*
Y1906100D01*
X1660990Y1903600D01*
G01Y1893600D02*
X1664710D01*
G01X1671840Y1896100D02*
X1672770Y1894641D01*
X1674010Y1893808D01*
X1675405Y1893600D01*
X1676645Y1893808D01*
X1677885Y1894850D01*
X1678660Y1896100D01*
X1678815Y1897350D01*
X1678505Y1898808D01*
X1677420Y1899850D01*
X1676335Y1900267D01*
X1674940D01*
G01X1676335D02*
X1677265Y1900892D01*
X1678040Y1901933D01*
X1678350Y1903183D01*
X1678040Y1904433D01*
X1677265Y1905475D01*
X1675870Y1906100D01*
X1674475Y1905892D01*
X1673080Y1905058D01*
G01X1687650Y1906100D02*
X1686410Y1905683D01*
X1685480Y1904642D01*
X1684860Y1903392D01*
X1684395Y1901725D01*
X1684240Y1899850D01*
X1684395Y1897975D01*
X1684860Y1896308D01*
X1685480Y1895058D01*
X1686410Y1894017D01*
X1687650Y1893600D01*
X1688890Y1894017D01*
X1689820Y1895058D01*
X1690440Y1896308D01*
X1690905Y1897975D01*
X1691060Y1899850D01*
X1690905Y1901725D01*
X1690440Y1903392D01*
X1689820Y1904642D01*
X1688890Y1905683D01*
X1687650Y1906100D01*
G01X1696640Y1895475D02*
X1697570Y1894433D01*
X1698655Y1893808D01*
X1700050Y1893600D01*
X1701445Y1894017D01*
X1702530Y1894850D01*
X1703305Y1896308D01*
X1703460Y1897975D01*
X1703150Y1899642D01*
X1702375Y1900683D01*
X1701290Y1901517D01*
X1700205Y1901725D01*
X1699120Y1901517D01*
X1697725Y1900683D01*
X1698190Y1906100D01*
X1702375D01*
G01X1675250Y1725000D02*
Y1737500D01*
X1673390Y1735000D01*
G01Y1725000D02*
X1677110D01*
G01X1684705Y1735417D02*
X1685635Y1736666D01*
X1686720Y1737292D01*
X1687960Y1737500D01*
X1689510Y1737083D01*
X1690595Y1736042D01*
X1690905Y1734792D01*
X1690750Y1733541D01*
X1690130Y1732500D01*
X1687030Y1730417D01*
X1685635Y1728958D01*
X1684705Y1726875D01*
X1684395Y1725000D01*
X1690905D01*
G01X1678505Y1707317D02*
X1679435Y1708566D01*
X1680520Y1709192D01*
X1681760Y1709400D01*
X1683310Y1708983D01*
X1684395Y1707942D01*
X1684705Y1706692D01*
X1684550Y1705441D01*
X1683930Y1704400D01*
X1680830Y1702317D01*
X1679435Y1700858D01*
X1678505Y1698775D01*
X1678195Y1696900D01*
X1684705D01*
G01X1671840Y1671300D02*
X1672770Y1669841D01*
X1674010Y1669008D01*
X1675405Y1668800D01*
X1676645Y1669008D01*
X1677885Y1670050D01*
X1678660Y1671300D01*
X1678815Y1672550D01*
X1678505Y1674008D01*
X1677420Y1675050D01*
X1676335Y1675467D01*
X1674940D01*
G01X1676335D02*
X1677265Y1676092D01*
X1678040Y1677133D01*
X1678350Y1678383D01*
X1678040Y1679633D01*
X1677265Y1680675D01*
X1675870Y1681300D01*
X1674475Y1681092D01*
X1673080Y1680258D01*
G01X1687650Y1681300D02*
X1686410Y1680883D01*
X1685480Y1679842D01*
X1684860Y1678592D01*
X1684395Y1676925D01*
X1684240Y1675050D01*
X1684395Y1673175D01*
X1684860Y1671508D01*
X1685480Y1670258D01*
X1686410Y1669217D01*
X1687650Y1668800D01*
X1688890Y1669217D01*
X1689820Y1670258D01*
X1690440Y1671508D01*
X1690905Y1673175D01*
X1691060Y1675050D01*
X1690905Y1676925D01*
X1690440Y1678592D01*
X1689820Y1679842D01*
X1688890Y1680883D01*
X1687650Y1681300D01*
G01X1671840Y1783700D02*
X1672770Y1782241D01*
X1674010Y1781408D01*
X1675405Y1781200D01*
X1676645Y1781408D01*
X1677885Y1782450D01*
X1678660Y1783700D01*
X1678815Y1784950D01*
X1678505Y1786408D01*
X1677420Y1787450D01*
X1676335Y1787867D01*
X1674940D01*
G01X1676335D02*
X1677265Y1788492D01*
X1678040Y1789533D01*
X1678350Y1790783D01*
X1678040Y1792033D01*
X1677265Y1793075D01*
X1675870Y1793700D01*
X1674475Y1793492D01*
X1673080Y1792658D01*
G01X1687650Y1793700D02*
X1686410Y1793283D01*
X1685480Y1792242D01*
X1684860Y1790992D01*
X1684395Y1789325D01*
X1684240Y1787450D01*
X1684395Y1785575D01*
X1684860Y1783908D01*
X1685480Y1782658D01*
X1686410Y1781617D01*
X1687650Y1781200D01*
X1688890Y1781617D01*
X1689820Y1782658D01*
X1690440Y1783908D01*
X1690905Y1785575D01*
X1691060Y1787450D01*
X1690905Y1789325D01*
X1690440Y1790992D01*
X1689820Y1792242D01*
X1688890Y1793283D01*
X1687650Y1793700D01*
G01X1675250Y1753100D02*
Y1765600D01*
X1673390Y1763100D01*
G01Y1753100D02*
X1677110D01*
G01X1687650Y1765600D02*
X1686410Y1765183D01*
X1685480Y1764142D01*
X1684860Y1762892D01*
X1684395Y1761225D01*
X1684240Y1759350D01*
X1684395Y1757475D01*
X1684860Y1755808D01*
X1685480Y1754558D01*
X1686410Y1753517D01*
X1687650Y1753100D01*
X1688890Y1753517D01*
X1689820Y1754558D01*
X1690440Y1755808D01*
X1690905Y1757475D01*
X1691060Y1759350D01*
X1690905Y1761225D01*
X1690440Y1762892D01*
X1689820Y1764142D01*
X1688890Y1765183D01*
X1687650Y1765600D01*
G01X1675250Y1837400D02*
Y1849900D01*
X1673390Y1847400D01*
G01Y1837400D02*
X1677110D01*
G01X1687650D02*
Y1849900D01*
X1685790Y1847400D01*
G01Y1837400D02*
X1689510D01*
G01X1678505Y1819717D02*
X1679435Y1820966D01*
X1680520Y1821592D01*
X1681760Y1821800D01*
X1683310Y1821383D01*
X1684395Y1820342D01*
X1684705Y1819092D01*
X1684550Y1817841D01*
X1683930Y1816800D01*
X1680830Y1814717D01*
X1679435Y1813258D01*
X1678505Y1811175D01*
X1678195Y1809300D01*
X1684705D01*
G01X19842Y213601D02*
X1970D01*
X1Y211632D01*
Y142932D01*
G01X-11724Y209441D02*
X-12057Y208908D01*
X-12257Y208308D01*
Y207774D01*
X-12057Y207241D01*
X-11724Y206841D01*
X-11257Y206641D01*
X-10790Y206774D01*
X-10390Y207108D01*
X-10124Y207708D01*
X-9990Y208508D01*
X-9724Y208974D01*
X-9257Y209174D01*
X-8790Y209041D01*
X-8457Y208708D01*
X-8257Y208241D01*
Y207774D01*
X-8390Y207308D01*
X-8724Y206908D01*
G01X-12257Y203441D02*
X-8257D01*
G01X-9590Y198841D02*
X-12257D01*
G01X-8524D02*
X-8457Y198974D01*
X-8324D01*
X-8257Y198841D01*
X-8324Y198708D01*
X-8457D01*
X-8524Y198841D01*
G01X-8257Y194241D02*
X-12257D01*
G01X-9590Y195174D02*
Y193308D01*
G01X-257Y200841D02*
X-9757D01*
G01X-5257Y199346D02*
X-257Y200841D01*
X-5257Y202336D01*
Y199346D01*
G01X1Y276002D02*
Y223050D01*
X1970Y221081D01*
X19883D01*
G02Y213601I0J-3740D01*
G01X19842D01*
G01X0Y727946D02*
Y423026D01*
X1969Y421057D01*
X19883D01*
G02Y413577I0J-3740D01*
G01X1969D01*
X0Y411608D01*
Y342908D01*
G01Y727946D02*
Y423026D01*
X1969Y421057D01*
X19883D01*
G02Y413577I0J-3740D01*
G01X1969D01*
X0Y411608D01*
Y342908D01*
G01X-11124Y516717D02*
X-11457Y516184D01*
X-11657Y515584D01*
Y515050D01*
X-11457Y514517D01*
X-11124Y514117D01*
X-10657Y513917D01*
X-10190Y514050D01*
X-9790Y514384D01*
X-9524Y514984D01*
X-9390Y515784D01*
X-9124Y516250D01*
X-8657Y516450D01*
X-8190Y516317D01*
X-7857Y515984D01*
X-7657Y515517D01*
Y515050D01*
X-7790Y514584D01*
X-8124Y514184D01*
G01X-11657Y510717D02*
X-7657D01*
G01X-8990Y506117D02*
X-11657D01*
G01X-7924D02*
X-7857Y506250D01*
X-7724D01*
X-7657Y506117D01*
X-7724Y505984D01*
X-7857D01*
X-7924Y506117D01*
G01X-7657Y501517D02*
X-11657D01*
G01X-8990Y502450D02*
Y500584D01*
G01X-157Y508317D02*
X-3157Y511317D01*
Y505317D01*
X-157Y508317D01*
X-8657D01*
G01X-11724Y818890D02*
X-12057Y818357D01*
X-12257Y817757D01*
Y817223D01*
X-12057Y816690D01*
X-11724Y816290D01*
X-11257Y816090D01*
X-10790Y816223D01*
X-10390Y816557D01*
X-10124Y817157D01*
X-9990Y817957D01*
X-9724Y818423D01*
X-9257Y818623D01*
X-8790Y818490D01*
X-8457Y818157D01*
X-8257Y817690D01*
Y817223D01*
X-8390Y816757D01*
X-8724Y816357D01*
G01X-12257Y812890D02*
X-8257D01*
G01X-9590Y808290D02*
X-12257D01*
G01X-8524D02*
X-8457Y808423D01*
X-8324D01*
X-8257Y808290D01*
X-8324Y808157D01*
X-8457D01*
X-8524Y808290D01*
G01X-8257Y803690D02*
X-12257D01*
G01X-9590Y804623D02*
Y802757D01*
G01X-257Y810290D02*
X-9757D01*
G01X-5257Y808795D02*
X-257Y810290D01*
X-5257Y811785D01*
Y808795D01*
G01X19842Y823050D02*
X1970D01*
X1Y821081D01*
Y752381D01*
G01Y885451D02*
Y832499D01*
X1970Y830530D01*
X19883D01*
G02Y823050I0J-3740D01*
G01X19842D01*
G01Y1197853D02*
X1970D01*
X1Y1195884D01*
Y1127184D01*
G01X-11724Y1193693D02*
X-12057Y1193160D01*
X-12257Y1192560D01*
Y1192026D01*
X-12057Y1191493D01*
X-11724Y1191093D01*
X-11257Y1190893D01*
X-10790Y1191026D01*
X-10390Y1191360D01*
X-10124Y1191960D01*
X-9990Y1192760D01*
X-9724Y1193226D01*
X-9257Y1193426D01*
X-8790Y1193293D01*
X-8457Y1192960D01*
X-8257Y1192493D01*
Y1192026D01*
X-8390Y1191560D01*
X-8724Y1191160D01*
G01X-12257Y1187693D02*
X-8257D01*
G01X-9590Y1183093D02*
X-12257D01*
G01X-8524D02*
X-8457Y1183226D01*
X-8324D01*
X-8257Y1183093D01*
X-8324Y1182960D01*
X-8457D01*
X-8524Y1183093D01*
G01X-8257Y1178493D02*
X-12257D01*
G01X-9590Y1179426D02*
Y1177560D01*
G01X-257Y1185093D02*
X-9757D01*
G01X-5257Y1183598D02*
X-257Y1185093D01*
X-5257Y1186588D01*
Y1183598D01*
G01X1Y1260254D02*
Y1207302D01*
X1970Y1205333D01*
X19883D01*
G02Y1197853I0J-3740D01*
G01X19842D01*
G01X0Y1712198D02*
Y1407278D01*
X1969Y1405309D01*
X19883D01*
G02Y1397829I0J-3740D01*
G01X1969D01*
X0Y1395860D01*
Y1327160D01*
G01Y1712198D02*
Y1407278D01*
X1969Y1405309D01*
X19883D01*
G02Y1397829I0J-3740D01*
G01X1969D01*
X0Y1395860D01*
Y1327160D01*
G01X-11124Y1500969D02*
X-11457Y1500436D01*
X-11657Y1499836D01*
Y1499302D01*
X-11457Y1498769D01*
X-11124Y1498369D01*
X-10657Y1498169D01*
X-10190Y1498302D01*
X-9790Y1498636D01*
X-9524Y1499236D01*
X-9390Y1500036D01*
X-9124Y1500502D01*
X-8657Y1500702D01*
X-8190Y1500569D01*
X-7857Y1500236D01*
X-7657Y1499769D01*
Y1499302D01*
X-7790Y1498836D01*
X-8124Y1498436D01*
G01X-11657Y1494969D02*
X-7657D01*
G01X-8990Y1490369D02*
X-11657D01*
G01X-7924D02*
X-7857Y1490502D01*
X-7724D01*
X-7657Y1490369D01*
X-7724Y1490236D01*
X-7857D01*
X-7924Y1490369D01*
G01X-7657Y1485769D02*
X-11657D01*
G01X-8990Y1486702D02*
Y1484836D01*
G01X-157Y1492569D02*
X-3157Y1495569D01*
Y1489569D01*
X-157Y1492569D01*
X-8657D01*
G01X-11724Y1803142D02*
X-12057Y1802609D01*
X-12257Y1802009D01*
Y1801475D01*
X-12057Y1800942D01*
X-11724Y1800542D01*
X-11257Y1800342D01*
X-10790Y1800475D01*
X-10390Y1800809D01*
X-10124Y1801409D01*
X-9990Y1802209D01*
X-9724Y1802675D01*
X-9257Y1802875D01*
X-8790Y1802742D01*
X-8457Y1802409D01*
X-8257Y1801942D01*
Y1801475D01*
X-8390Y1801009D01*
X-8724Y1800609D01*
G01X-12257Y1797142D02*
X-8257D01*
G01X-9590Y1792542D02*
X-12257D01*
G01X-8524D02*
X-8457Y1792675D01*
X-8324D01*
X-8257Y1792542D01*
X-8324Y1792409D01*
X-8457D01*
X-8524Y1792542D01*
G01X-8257Y1787942D02*
X-12257D01*
G01X-9590Y1788875D02*
Y1787009D01*
G01X-257Y1794542D02*
X-9757D01*
G01X-5257Y1793047D02*
X-257Y1794542D01*
X-5257Y1796037D01*
Y1793047D01*
G01X19842Y1807302D02*
X1970D01*
X1Y1805333D01*
Y1736633D01*
G01Y1869703D02*
Y1816751D01*
X1970Y1814782D01*
X19883D01*
G02Y1807302I0J-3740D01*
G01X19842D01*
G01X69598Y28794D02*
X70065Y29194D01*
X70331Y29728D01*
X70398Y30328D01*
X70331Y30861D01*
X69998Y31394D01*
X69598Y31728D01*
X69198Y31794D01*
X68731Y31661D01*
X68398Y31194D01*
X68265Y30728D01*
Y30128D01*
G01Y30728D02*
X68065Y31128D01*
X67731Y31461D01*
X67331Y31594D01*
X66931Y31461D01*
X66598Y31128D01*
X66398Y30528D01*
X66465Y29928D01*
X66731Y29328D01*
G01X67065Y33594D02*
X66665Y33994D01*
X66465Y34461D01*
X66398Y34994D01*
X66531Y35661D01*
X66865Y36128D01*
X67265Y36261D01*
X67665Y36194D01*
X67998Y35928D01*
X68665Y34594D01*
X69131Y33994D01*
X69798Y33594D01*
X70398Y33461D01*
Y36261D01*
G01Y38061D02*
X66398Y40861D01*
G01Y38061D02*
X70398Y40861D01*
G01Y43928D02*
X69531Y44061D01*
X68798Y44261D01*
X68131Y44528D01*
X67398Y44861D01*
X66398Y45394D01*
Y42728D01*
G01X69798Y47194D02*
X70131Y47594D01*
X70331Y48061D01*
X70398Y48661D01*
X70265Y49261D01*
X69998Y49728D01*
X69531Y50061D01*
X68998Y50128D01*
X68465Y49994D01*
X68131Y49661D01*
X67865Y49194D01*
X67798Y48728D01*
X67865Y48261D01*
X68131Y47661D01*
X66398Y47861D01*
Y49661D01*
G01X69598Y157794D02*
X70065Y158194D01*
X70331Y158728D01*
X70398Y159328D01*
X70331Y159861D01*
X69998Y160394D01*
X69598Y160728D01*
X69198Y160794D01*
X68731Y160661D01*
X68398Y160194D01*
X68265Y159728D01*
Y159128D01*
G01Y159728D02*
X68065Y160128D01*
X67731Y160461D01*
X67331Y160594D01*
X66931Y160461D01*
X66598Y160128D01*
X66398Y159528D01*
X66465Y158928D01*
X66731Y158328D01*
G01X67065Y162594D02*
X66665Y162994D01*
X66465Y163461D01*
X66398Y163994D01*
X66531Y164661D01*
X66865Y165128D01*
X67265Y165261D01*
X67665Y165194D01*
X67998Y164928D01*
X68665Y163594D01*
X69131Y162994D01*
X69798Y162594D01*
X70398Y162461D01*
Y165261D01*
G01Y167061D02*
X66398Y169861D01*
G01Y167061D02*
X70398Y169861D01*
G01Y172928D02*
X69531Y173061D01*
X68798Y173261D01*
X68131Y173528D01*
X67398Y173861D01*
X66398Y174394D01*
Y171728D01*
G01X69798Y176194D02*
X70131Y176594D01*
X70331Y177061D01*
X70398Y177661D01*
X70265Y178261D01*
X69998Y178728D01*
X69531Y179061D01*
X68998Y179128D01*
X68465Y178994D01*
X68131Y178661D01*
X67865Y178194D01*
X67798Y177728D01*
X67865Y177261D01*
X68131Y176661D01*
X66398Y176861D01*
Y178661D01*
G01X69598Y434306D02*
X70065Y434706D01*
X70331Y435240D01*
X70398Y435840D01*
X70331Y436373D01*
X69998Y436906D01*
X69598Y437240D01*
X69198Y437306D01*
X68731Y437173D01*
X68398Y436706D01*
X68265Y436240D01*
Y435640D01*
G01Y436240D02*
X68065Y436640D01*
X67731Y436973D01*
X67331Y437106D01*
X66931Y436973D01*
X66598Y436640D01*
X66398Y436040D01*
X66465Y435440D01*
X66731Y434840D01*
G01X67065Y439106D02*
X66665Y439506D01*
X66465Y439973D01*
X66398Y440506D01*
X66531Y441173D01*
X66865Y441640D01*
X67265Y441773D01*
X67665Y441706D01*
X67998Y441440D01*
X68665Y440106D01*
X69131Y439506D01*
X69798Y439106D01*
X70398Y438973D01*
Y441773D01*
G01Y443573D02*
X66398Y446373D01*
G01Y443573D02*
X70398Y446373D01*
G01Y449440D02*
X69531Y449573D01*
X68798Y449773D01*
X68131Y450040D01*
X67398Y450373D01*
X66398Y450906D01*
Y448240D01*
G01X69798Y452706D02*
X70131Y453106D01*
X70331Y453573D01*
X70398Y454173D01*
X70265Y454773D01*
X69998Y455240D01*
X69531Y455573D01*
X68998Y455640D01*
X68465Y455506D01*
X68131Y455173D01*
X67865Y454706D01*
X67798Y454240D01*
X67865Y453773D01*
X68131Y453173D01*
X66398Y453373D01*
Y455173D01*
G01X69598Y563306D02*
X70065Y563706D01*
X70331Y564240D01*
X70398Y564840D01*
X70331Y565373D01*
X69998Y565906D01*
X69598Y566240D01*
X69198Y566306D01*
X68731Y566173D01*
X68398Y565706D01*
X68265Y565240D01*
Y564640D01*
G01Y565240D02*
X68065Y565640D01*
X67731Y565973D01*
X67331Y566106D01*
X66931Y565973D01*
X66598Y565640D01*
X66398Y565040D01*
X66465Y564440D01*
X66731Y563840D01*
G01X67065Y568106D02*
X66665Y568506D01*
X66465Y568973D01*
X66398Y569506D01*
X66531Y570173D01*
X66865Y570640D01*
X67265Y570773D01*
X67665Y570706D01*
X67998Y570440D01*
X68665Y569106D01*
X69131Y568506D01*
X69798Y568106D01*
X70398Y567973D01*
Y570773D01*
G01Y572573D02*
X66398Y575373D01*
G01Y572573D02*
X70398Y575373D01*
G01Y578440D02*
X69531Y578573D01*
X68798Y578773D01*
X68131Y579040D01*
X67398Y579373D01*
X66398Y579906D01*
Y577240D01*
G01X69798Y581706D02*
X70131Y582106D01*
X70331Y582573D01*
X70398Y583173D01*
X70265Y583773D01*
X69998Y584240D01*
X69531Y584573D01*
X68998Y584640D01*
X68465Y584506D01*
X68131Y584173D01*
X67865Y583706D01*
X67798Y583240D01*
X67865Y582773D01*
X68131Y582173D01*
X66398Y582373D01*
Y584173D01*
G01X69598Y839818D02*
X70065Y840218D01*
X70331Y840752D01*
X70398Y841352D01*
X70331Y841885D01*
X69998Y842418D01*
X69598Y842752D01*
X69198Y842818D01*
X68731Y842685D01*
X68398Y842218D01*
X68265Y841752D01*
Y841152D01*
G01Y841752D02*
X68065Y842152D01*
X67731Y842485D01*
X67331Y842618D01*
X66931Y842485D01*
X66598Y842152D01*
X66398Y841552D01*
X66465Y840952D01*
X66731Y840352D01*
G01X67065Y844618D02*
X66665Y845018D01*
X66465Y845485D01*
X66398Y846018D01*
X66531Y846685D01*
X66865Y847152D01*
X67265Y847285D01*
X67665Y847218D01*
X67998Y846952D01*
X68665Y845618D01*
X69131Y845018D01*
X69798Y844618D01*
X70398Y844485D01*
Y847285D01*
G01Y849085D02*
X66398Y851885D01*
G01Y849085D02*
X70398Y851885D01*
G01Y854952D02*
X69531Y855085D01*
X68798Y855285D01*
X68131Y855552D01*
X67398Y855885D01*
X66398Y856418D01*
Y853752D01*
G01X69798Y858218D02*
X70131Y858618D01*
X70331Y859085D01*
X70398Y859685D01*
X70265Y860285D01*
X69998Y860752D01*
X69531Y861085D01*
X68998Y861152D01*
X68465Y861018D01*
X68131Y860685D01*
X67865Y860218D01*
X67798Y859752D01*
X67865Y859285D01*
X68131Y858685D01*
X66398Y858885D01*
Y860685D01*
G01X69598Y968818D02*
X70065Y969218D01*
X70331Y969752D01*
X70398Y970352D01*
X70331Y970885D01*
X69998Y971418D01*
X69598Y971752D01*
X69198Y971818D01*
X68731Y971685D01*
X68398Y971218D01*
X68265Y970752D01*
Y970152D01*
G01Y970752D02*
X68065Y971152D01*
X67731Y971485D01*
X67331Y971618D01*
X66931Y971485D01*
X66598Y971152D01*
X66398Y970552D01*
X66465Y969952D01*
X66731Y969352D01*
G01X67065Y973618D02*
X66665Y974018D01*
X66465Y974485D01*
X66398Y975018D01*
X66531Y975685D01*
X66865Y976152D01*
X67265Y976285D01*
X67665Y976218D01*
X67998Y975952D01*
X68665Y974618D01*
X69131Y974018D01*
X69798Y973618D01*
X70398Y973485D01*
Y976285D01*
G01Y978085D02*
X66398Y980885D01*
G01Y978085D02*
X70398Y980885D01*
G01Y983952D02*
X69531Y984085D01*
X68798Y984285D01*
X68131Y984552D01*
X67398Y984885D01*
X66398Y985418D01*
Y982752D01*
G01X69798Y987218D02*
X70131Y987618D01*
X70331Y988085D01*
X70398Y988685D01*
X70265Y989285D01*
X69998Y989752D01*
X69531Y990085D01*
X68998Y990152D01*
X68465Y990018D01*
X68131Y989685D01*
X67865Y989218D01*
X67798Y988752D01*
X67865Y988285D01*
X68131Y987685D01*
X66398Y987885D01*
Y989685D01*
G01X69598Y1245330D02*
X70065Y1245730D01*
X70331Y1246264D01*
X70398Y1246864D01*
X70331Y1247397D01*
X69998Y1247930D01*
X69598Y1248264D01*
X69198Y1248330D01*
X68731Y1248197D01*
X68398Y1247730D01*
X68265Y1247264D01*
Y1246664D01*
G01Y1247264D02*
X68065Y1247664D01*
X67731Y1247997D01*
X67331Y1248130D01*
X66931Y1247997D01*
X66598Y1247664D01*
X66398Y1247064D01*
X66465Y1246464D01*
X66731Y1245864D01*
G01X67065Y1250130D02*
X66665Y1250530D01*
X66465Y1250997D01*
X66398Y1251530D01*
X66531Y1252197D01*
X66865Y1252664D01*
X67265Y1252797D01*
X67665Y1252730D01*
X67998Y1252464D01*
X68665Y1251130D01*
X69131Y1250530D01*
X69798Y1250130D01*
X70398Y1249997D01*
Y1252797D01*
G01Y1254597D02*
X66398Y1257397D01*
G01Y1254597D02*
X70398Y1257397D01*
G01Y1260464D02*
X69531Y1260597D01*
X68798Y1260797D01*
X68131Y1261064D01*
X67398Y1261397D01*
X66398Y1261930D01*
Y1259264D01*
G01X69798Y1263730D02*
X70131Y1264130D01*
X70331Y1264597D01*
X70398Y1265197D01*
X70265Y1265797D01*
X69998Y1266264D01*
X69531Y1266597D01*
X68998Y1266664D01*
X68465Y1266530D01*
X68131Y1266197D01*
X67865Y1265730D01*
X67798Y1265264D01*
X67865Y1264797D01*
X68131Y1264197D01*
X66398Y1264397D01*
Y1266197D01*
G01X69598Y1374330D02*
X70065Y1374730D01*
X70331Y1375264D01*
X70398Y1375864D01*
X70331Y1376397D01*
X69998Y1376930D01*
X69598Y1377264D01*
X69198Y1377330D01*
X68731Y1377197D01*
X68398Y1376730D01*
X68265Y1376264D01*
Y1375664D01*
G01Y1376264D02*
X68065Y1376664D01*
X67731Y1376997D01*
X67331Y1377130D01*
X66931Y1376997D01*
X66598Y1376664D01*
X66398Y1376064D01*
X66465Y1375464D01*
X66731Y1374864D01*
G01X67065Y1379130D02*
X66665Y1379530D01*
X66465Y1379997D01*
X66398Y1380530D01*
X66531Y1381197D01*
X66865Y1381664D01*
X67265Y1381797D01*
X67665Y1381730D01*
X67998Y1381464D01*
X68665Y1380130D01*
X69131Y1379530D01*
X69798Y1379130D01*
X70398Y1378997D01*
Y1381797D01*
G01Y1383597D02*
X66398Y1386397D01*
G01Y1383597D02*
X70398Y1386397D01*
G01Y1389464D02*
X69531Y1389597D01*
X68798Y1389797D01*
X68131Y1390064D01*
X67398Y1390397D01*
X66398Y1390930D01*
Y1388264D01*
G01X69798Y1392730D02*
X70131Y1393130D01*
X70331Y1393597D01*
X70398Y1394197D01*
X70265Y1394797D01*
X69998Y1395264D01*
X69531Y1395597D01*
X68998Y1395664D01*
X68465Y1395530D01*
X68131Y1395197D01*
X67865Y1394730D01*
X67798Y1394264D01*
X67865Y1393797D01*
X68131Y1393197D01*
X66398Y1393397D01*
Y1395197D01*
G01X69598Y1650842D02*
X70065Y1651242D01*
X70331Y1651776D01*
X70398Y1652376D01*
X70331Y1652909D01*
X69998Y1653442D01*
X69598Y1653776D01*
X69198Y1653842D01*
X68731Y1653709D01*
X68398Y1653242D01*
X68265Y1652776D01*
Y1652176D01*
G01Y1652776D02*
X68065Y1653176D01*
X67731Y1653509D01*
X67331Y1653642D01*
X66931Y1653509D01*
X66598Y1653176D01*
X66398Y1652576D01*
X66465Y1651976D01*
X66731Y1651376D01*
G01X67065Y1655642D02*
X66665Y1656042D01*
X66465Y1656509D01*
X66398Y1657042D01*
X66531Y1657709D01*
X66865Y1658176D01*
X67265Y1658309D01*
X67665Y1658242D01*
X67998Y1657976D01*
X68665Y1656642D01*
X69131Y1656042D01*
X69798Y1655642D01*
X70398Y1655509D01*
Y1658309D01*
G01Y1660109D02*
X66398Y1662909D01*
G01Y1660109D02*
X70398Y1662909D01*
G01Y1665976D02*
X69531Y1666109D01*
X68798Y1666309D01*
X68131Y1666576D01*
X67398Y1666909D01*
X66398Y1667442D01*
Y1664776D01*
G01X69798Y1669242D02*
X70131Y1669642D01*
X70331Y1670109D01*
X70398Y1670709D01*
X70265Y1671309D01*
X69998Y1671776D01*
X69531Y1672109D01*
X68998Y1672176D01*
X68465Y1672042D01*
X68131Y1671709D01*
X67865Y1671242D01*
X67798Y1670776D01*
X67865Y1670309D01*
X68131Y1669709D01*
X66398Y1669909D01*
Y1671709D01*
G01X69598Y1779842D02*
X70065Y1780242D01*
X70331Y1780776D01*
X70398Y1781376D01*
X70331Y1781909D01*
X69998Y1782442D01*
X69598Y1782776D01*
X69198Y1782842D01*
X68731Y1782709D01*
X68398Y1782242D01*
X68265Y1781776D01*
Y1781176D01*
G01Y1781776D02*
X68065Y1782176D01*
X67731Y1782509D01*
X67331Y1782642D01*
X66931Y1782509D01*
X66598Y1782176D01*
X66398Y1781576D01*
X66465Y1780976D01*
X66731Y1780376D01*
G01X67065Y1784642D02*
X66665Y1785042D01*
X66465Y1785509D01*
X66398Y1786042D01*
X66531Y1786709D01*
X66865Y1787176D01*
X67265Y1787309D01*
X67665Y1787242D01*
X67998Y1786976D01*
X68665Y1785642D01*
X69131Y1785042D01*
X69798Y1784642D01*
X70398Y1784509D01*
Y1787309D01*
G01Y1789109D02*
X66398Y1791909D01*
G01Y1789109D02*
X70398Y1791909D01*
G01Y1794976D02*
X69531Y1795109D01*
X68798Y1795309D01*
X68131Y1795576D01*
X67398Y1795909D01*
X66398Y1796442D01*
Y1793776D01*
G01X69798Y1798242D02*
X70131Y1798642D01*
X70331Y1799109D01*
X70398Y1799709D01*
X70265Y1800309D01*
X69998Y1800776D01*
X69531Y1801109D01*
X68998Y1801176D01*
X68465Y1801042D01*
X68131Y1800709D01*
X67865Y1800242D01*
X67798Y1799776D01*
X67865Y1799309D01*
X68131Y1798709D01*
X66398Y1798909D01*
Y1800709D01*
G01X169023Y190950D02*
X169490Y191350D01*
X169756Y191884D01*
X169823Y192484D01*
X169756Y193017D01*
X169423Y193550D01*
X169023Y193884D01*
X168623Y193950D01*
X168156Y193817D01*
X167823Y193350D01*
X167690Y192884D01*
Y192284D01*
G01Y192884D02*
X167490Y193284D01*
X167156Y193617D01*
X166756Y193750D01*
X166356Y193617D01*
X166023Y193284D01*
X165823Y192684D01*
X165890Y192084D01*
X166156Y191484D01*
G01X166490Y195750D02*
X166090Y196150D01*
X165890Y196617D01*
X165823Y197150D01*
X165956Y197817D01*
X166290Y198284D01*
X166690Y198417D01*
X167090Y198350D01*
X167423Y198084D01*
X168090Y196750D01*
X168556Y196150D01*
X169223Y195750D01*
X169823Y195617D01*
Y198417D01*
G01Y200217D02*
X165823Y203017D01*
G01Y200217D02*
X169823Y203017D01*
G01Y206084D02*
X168956Y206217D01*
X168223Y206417D01*
X167556Y206684D01*
X166823Y207017D01*
X165823Y207550D01*
Y204884D01*
G01X169223Y209350D02*
X169556Y209750D01*
X169756Y210217D01*
X169823Y210817D01*
X169690Y211417D01*
X169423Y211884D01*
X168956Y212217D01*
X168423Y212284D01*
X167890Y212150D01*
X167556Y211817D01*
X167290Y211350D01*
X167223Y210884D01*
X167290Y210417D01*
X167556Y209817D01*
X165823Y210017D01*
Y211817D01*
G01X169023Y319950D02*
X169490Y320350D01*
X169756Y320884D01*
X169823Y321484D01*
X169756Y322017D01*
X169423Y322550D01*
X169023Y322884D01*
X168623Y322950D01*
X168156Y322817D01*
X167823Y322350D01*
X167690Y321884D01*
Y321284D01*
G01Y321884D02*
X167490Y322284D01*
X167156Y322617D01*
X166756Y322750D01*
X166356Y322617D01*
X166023Y322284D01*
X165823Y321684D01*
X165890Y321084D01*
X166156Y320484D01*
G01X166490Y324750D02*
X166090Y325150D01*
X165890Y325617D01*
X165823Y326150D01*
X165956Y326817D01*
X166290Y327284D01*
X166690Y327417D01*
X167090Y327350D01*
X167423Y327084D01*
X168090Y325750D01*
X168556Y325150D01*
X169223Y324750D01*
X169823Y324617D01*
Y327417D01*
G01Y329217D02*
X165823Y332017D01*
G01Y329217D02*
X169823Y332017D01*
G01Y335084D02*
X168956Y335217D01*
X168223Y335417D01*
X167556Y335684D01*
X166823Y336017D01*
X165823Y336550D01*
Y333884D01*
G01X169223Y338350D02*
X169556Y338750D01*
X169756Y339217D01*
X169823Y339817D01*
X169690Y340417D01*
X169423Y340884D01*
X168956Y341217D01*
X168423Y341284D01*
X167890Y341150D01*
X167556Y340817D01*
X167290Y340350D01*
X167223Y339884D01*
X167290Y339417D01*
X167556Y338817D01*
X165823Y339017D01*
Y340817D01*
G01X169023Y596462D02*
X169490Y596862D01*
X169756Y597396D01*
X169823Y597996D01*
X169756Y598529D01*
X169423Y599062D01*
X169023Y599396D01*
X168623Y599462D01*
X168156Y599329D01*
X167823Y598862D01*
X167690Y598396D01*
Y597796D01*
G01Y598396D02*
X167490Y598796D01*
X167156Y599129D01*
X166756Y599262D01*
X166356Y599129D01*
X166023Y598796D01*
X165823Y598196D01*
X165890Y597596D01*
X166156Y596996D01*
G01X166490Y601262D02*
X166090Y601662D01*
X165890Y602129D01*
X165823Y602662D01*
X165956Y603329D01*
X166290Y603796D01*
X166690Y603929D01*
X167090Y603862D01*
X167423Y603596D01*
X168090Y602262D01*
X168556Y601662D01*
X169223Y601262D01*
X169823Y601129D01*
Y603929D01*
G01Y605729D02*
X165823Y608529D01*
G01Y605729D02*
X169823Y608529D01*
G01Y611596D02*
X168956Y611729D01*
X168223Y611929D01*
X167556Y612196D01*
X166823Y612529D01*
X165823Y613062D01*
Y610396D01*
G01X169223Y614862D02*
X169556Y615262D01*
X169756Y615729D01*
X169823Y616329D01*
X169690Y616929D01*
X169423Y617396D01*
X168956Y617729D01*
X168423Y617796D01*
X167890Y617662D01*
X167556Y617329D01*
X167290Y616862D01*
X167223Y616396D01*
X167290Y615929D01*
X167556Y615329D01*
X165823Y615529D01*
Y617329D01*
G01X169023Y725462D02*
X169490Y725862D01*
X169756Y726396D01*
X169823Y726996D01*
X169756Y727529D01*
X169423Y728062D01*
X169023Y728396D01*
X168623Y728462D01*
X168156Y728329D01*
X167823Y727862D01*
X167690Y727396D01*
Y726796D01*
G01Y727396D02*
X167490Y727796D01*
X167156Y728129D01*
X166756Y728262D01*
X166356Y728129D01*
X166023Y727796D01*
X165823Y727196D01*
X165890Y726596D01*
X166156Y725996D01*
G01X166490Y730262D02*
X166090Y730662D01*
X165890Y731129D01*
X165823Y731662D01*
X165956Y732329D01*
X166290Y732796D01*
X166690Y732929D01*
X167090Y732862D01*
X167423Y732596D01*
X168090Y731262D01*
X168556Y730662D01*
X169223Y730262D01*
X169823Y730129D01*
Y732929D01*
G01Y734729D02*
X165823Y737529D01*
G01Y734729D02*
X169823Y737529D01*
G01Y740596D02*
X168956Y740729D01*
X168223Y740929D01*
X167556Y741196D01*
X166823Y741529D01*
X165823Y742062D01*
Y739396D01*
G01X169223Y743862D02*
X169556Y744262D01*
X169756Y744729D01*
X169823Y745329D01*
X169690Y745929D01*
X169423Y746396D01*
X168956Y746729D01*
X168423Y746796D01*
X167890Y746662D01*
X167556Y746329D01*
X167290Y745862D01*
X167223Y745396D01*
X167290Y744929D01*
X167556Y744329D01*
X165823Y744529D01*
Y746329D01*
G01X169023Y1001974D02*
X169490Y1002374D01*
X169756Y1002908D01*
X169823Y1003508D01*
X169756Y1004041D01*
X169423Y1004574D01*
X169023Y1004908D01*
X168623Y1004974D01*
X168156Y1004841D01*
X167823Y1004374D01*
X167690Y1003908D01*
Y1003308D01*
G01Y1003908D02*
X167490Y1004308D01*
X167156Y1004641D01*
X166756Y1004774D01*
X166356Y1004641D01*
X166023Y1004308D01*
X165823Y1003708D01*
X165890Y1003108D01*
X166156Y1002508D01*
G01X166490Y1006774D02*
X166090Y1007174D01*
X165890Y1007641D01*
X165823Y1008174D01*
X165956Y1008841D01*
X166290Y1009308D01*
X166690Y1009441D01*
X167090Y1009374D01*
X167423Y1009108D01*
X168090Y1007774D01*
X168556Y1007174D01*
X169223Y1006774D01*
X169823Y1006641D01*
Y1009441D01*
G01Y1011241D02*
X165823Y1014041D01*
G01Y1011241D02*
X169823Y1014041D01*
G01Y1017108D02*
X168956Y1017241D01*
X168223Y1017441D01*
X167556Y1017708D01*
X166823Y1018041D01*
X165823Y1018574D01*
Y1015908D01*
G01X169223Y1020374D02*
X169556Y1020774D01*
X169756Y1021241D01*
X169823Y1021841D01*
X169690Y1022441D01*
X169423Y1022908D01*
X168956Y1023241D01*
X168423Y1023308D01*
X167890Y1023174D01*
X167556Y1022841D01*
X167290Y1022374D01*
X167223Y1021908D01*
X167290Y1021441D01*
X167556Y1020841D01*
X165823Y1021041D01*
Y1022841D01*
G01X169023Y1130974D02*
X169490Y1131374D01*
X169756Y1131908D01*
X169823Y1132508D01*
X169756Y1133041D01*
X169423Y1133574D01*
X169023Y1133908D01*
X168623Y1133974D01*
X168156Y1133841D01*
X167823Y1133374D01*
X167690Y1132908D01*
Y1132308D01*
G01Y1132908D02*
X167490Y1133308D01*
X167156Y1133641D01*
X166756Y1133774D01*
X166356Y1133641D01*
X166023Y1133308D01*
X165823Y1132708D01*
X165890Y1132108D01*
X166156Y1131508D01*
G01X166490Y1135774D02*
X166090Y1136174D01*
X165890Y1136641D01*
X165823Y1137174D01*
X165956Y1137841D01*
X166290Y1138308D01*
X166690Y1138441D01*
X167090Y1138374D01*
X167423Y1138108D01*
X168090Y1136774D01*
X168556Y1136174D01*
X169223Y1135774D01*
X169823Y1135641D01*
Y1138441D01*
G01Y1140241D02*
X165823Y1143041D01*
G01Y1140241D02*
X169823Y1143041D01*
G01Y1146108D02*
X168956Y1146241D01*
X168223Y1146441D01*
X167556Y1146708D01*
X166823Y1147041D01*
X165823Y1147574D01*
Y1144908D01*
G01X169223Y1149374D02*
X169556Y1149774D01*
X169756Y1150241D01*
X169823Y1150841D01*
X169690Y1151441D01*
X169423Y1151908D01*
X168956Y1152241D01*
X168423Y1152308D01*
X167890Y1152174D01*
X167556Y1151841D01*
X167290Y1151374D01*
X167223Y1150908D01*
X167290Y1150441D01*
X167556Y1149841D01*
X165823Y1150041D01*
Y1151841D01*
G01X169023Y1407486D02*
X169490Y1407886D01*
X169756Y1408420D01*
X169823Y1409020D01*
X169756Y1409553D01*
X169423Y1410086D01*
X169023Y1410420D01*
X168623Y1410486D01*
X168156Y1410353D01*
X167823Y1409886D01*
X167690Y1409420D01*
Y1408820D01*
G01Y1409420D02*
X167490Y1409820D01*
X167156Y1410153D01*
X166756Y1410286D01*
X166356Y1410153D01*
X166023Y1409820D01*
X165823Y1409220D01*
X165890Y1408620D01*
X166156Y1408020D01*
G01X166490Y1412286D02*
X166090Y1412686D01*
X165890Y1413153D01*
X165823Y1413686D01*
X165956Y1414353D01*
X166290Y1414820D01*
X166690Y1414953D01*
X167090Y1414886D01*
X167423Y1414620D01*
X168090Y1413286D01*
X168556Y1412686D01*
X169223Y1412286D01*
X169823Y1412153D01*
Y1414953D01*
G01Y1416753D02*
X165823Y1419553D01*
G01Y1416753D02*
X169823Y1419553D01*
G01Y1422620D02*
X168956Y1422753D01*
X168223Y1422953D01*
X167556Y1423220D01*
X166823Y1423553D01*
X165823Y1424086D01*
Y1421420D01*
G01X169223Y1425886D02*
X169556Y1426286D01*
X169756Y1426753D01*
X169823Y1427353D01*
X169690Y1427953D01*
X169423Y1428420D01*
X168956Y1428753D01*
X168423Y1428820D01*
X167890Y1428686D01*
X167556Y1428353D01*
X167290Y1427886D01*
X167223Y1427420D01*
X167290Y1426953D01*
X167556Y1426353D01*
X165823Y1426553D01*
Y1428353D01*
G01X169023Y1536486D02*
X169490Y1536886D01*
X169756Y1537420D01*
X169823Y1538020D01*
X169756Y1538553D01*
X169423Y1539086D01*
X169023Y1539420D01*
X168623Y1539486D01*
X168156Y1539353D01*
X167823Y1538886D01*
X167690Y1538420D01*
Y1537820D01*
G01Y1538420D02*
X167490Y1538820D01*
X167156Y1539153D01*
X166756Y1539286D01*
X166356Y1539153D01*
X166023Y1538820D01*
X165823Y1538220D01*
X165890Y1537620D01*
X166156Y1537020D01*
G01X166490Y1541286D02*
X166090Y1541686D01*
X165890Y1542153D01*
X165823Y1542686D01*
X165956Y1543353D01*
X166290Y1543820D01*
X166690Y1543953D01*
X167090Y1543886D01*
X167423Y1543620D01*
X168090Y1542286D01*
X168556Y1541686D01*
X169223Y1541286D01*
X169823Y1541153D01*
Y1543953D01*
G01Y1545753D02*
X165823Y1548553D01*
G01Y1545753D02*
X169823Y1548553D01*
G01Y1551620D02*
X168956Y1551753D01*
X168223Y1551953D01*
X167556Y1552220D01*
X166823Y1552553D01*
X165823Y1553086D01*
Y1550420D01*
G01X169223Y1554886D02*
X169556Y1555286D01*
X169756Y1555753D01*
X169823Y1556353D01*
X169690Y1556953D01*
X169423Y1557420D01*
X168956Y1557753D01*
X168423Y1557820D01*
X167890Y1557686D01*
X167556Y1557353D01*
X167290Y1556886D01*
X167223Y1556420D01*
X167290Y1555953D01*
X167556Y1555353D01*
X165823Y1555553D01*
Y1557353D01*
G01X169023Y1812998D02*
X169490Y1813398D01*
X169756Y1813932D01*
X169823Y1814532D01*
X169756Y1815065D01*
X169423Y1815598D01*
X169023Y1815932D01*
X168623Y1815998D01*
X168156Y1815865D01*
X167823Y1815398D01*
X167690Y1814932D01*
Y1814332D01*
G01Y1814932D02*
X167490Y1815332D01*
X167156Y1815665D01*
X166756Y1815798D01*
X166356Y1815665D01*
X166023Y1815332D01*
X165823Y1814732D01*
X165890Y1814132D01*
X166156Y1813532D01*
G01X166490Y1817798D02*
X166090Y1818198D01*
X165890Y1818665D01*
X165823Y1819198D01*
X165956Y1819865D01*
X166290Y1820332D01*
X166690Y1820465D01*
X167090Y1820398D01*
X167423Y1820132D01*
X168090Y1818798D01*
X168556Y1818198D01*
X169223Y1817798D01*
X169823Y1817665D01*
Y1820465D01*
G01Y1822265D02*
X165823Y1825065D01*
G01Y1822265D02*
X169823Y1825065D01*
G01Y1828132D02*
X168956Y1828265D01*
X168223Y1828465D01*
X167556Y1828732D01*
X166823Y1829065D01*
X165823Y1829598D01*
Y1826932D01*
G01X169223Y1831398D02*
X169556Y1831798D01*
X169756Y1832265D01*
X169823Y1832865D01*
X169690Y1833465D01*
X169423Y1833932D01*
X168956Y1834265D01*
X168423Y1834332D01*
X167890Y1834198D01*
X167556Y1833865D01*
X167290Y1833398D01*
X167223Y1832932D01*
X167290Y1832465D01*
X167556Y1831865D01*
X165823Y1832065D01*
Y1833865D01*
G01X169023Y1941998D02*
X169490Y1942398D01*
X169756Y1942932D01*
X169823Y1943532D01*
X169756Y1944065D01*
X169423Y1944598D01*
X169023Y1944932D01*
X168623Y1944998D01*
X168156Y1944865D01*
X167823Y1944398D01*
X167690Y1943932D01*
Y1943332D01*
G01Y1943932D02*
X167490Y1944332D01*
X167156Y1944665D01*
X166756Y1944798D01*
X166356Y1944665D01*
X166023Y1944332D01*
X165823Y1943732D01*
X165890Y1943132D01*
X166156Y1942532D01*
G01X166490Y1946798D02*
X166090Y1947198D01*
X165890Y1947665D01*
X165823Y1948198D01*
X165956Y1948865D01*
X166290Y1949332D01*
X166690Y1949465D01*
X167090Y1949398D01*
X167423Y1949132D01*
X168090Y1947798D01*
X168556Y1947198D01*
X169223Y1946798D01*
X169823Y1946665D01*
Y1949465D01*
G01Y1951265D02*
X165823Y1954065D01*
G01Y1951265D02*
X169823Y1954065D01*
G01Y1957132D02*
X168956Y1957265D01*
X168223Y1957465D01*
X167556Y1957732D01*
X166823Y1958065D01*
X165823Y1958598D01*
Y1955932D01*
G01X169223Y1960398D02*
X169556Y1960798D01*
X169756Y1961265D01*
X169823Y1961865D01*
X169690Y1962465D01*
X169423Y1962932D01*
X168956Y1963265D01*
X168423Y1963332D01*
X167890Y1963198D01*
X167556Y1962865D01*
X167290Y1962398D01*
X167223Y1961932D01*
X167290Y1961465D01*
X167556Y1960865D01*
X165823Y1961065D01*
Y1962865D01*
G01X897369Y190950D02*
X897836Y191350D01*
X898102Y191884D01*
X898169Y192484D01*
X898102Y193017D01*
X897769Y193550D01*
X897369Y193884D01*
X896969Y193950D01*
X896502Y193817D01*
X896169Y193350D01*
X896036Y192884D01*
Y192284D01*
G01Y192884D02*
X895836Y193284D01*
X895502Y193617D01*
X895102Y193750D01*
X894702Y193617D01*
X894369Y193284D01*
X894169Y192684D01*
X894236Y192084D01*
X894502Y191484D01*
G01X894836Y195750D02*
X894436Y196150D01*
X894236Y196617D01*
X894169Y197150D01*
X894302Y197817D01*
X894636Y198284D01*
X895036Y198417D01*
X895436Y198350D01*
X895769Y198084D01*
X896436Y196750D01*
X896902Y196150D01*
X897569Y195750D01*
X898169Y195617D01*
Y198417D01*
G01Y200217D02*
X894169Y203017D01*
G01Y200217D02*
X898169Y203017D01*
G01Y206084D02*
X897302Y206217D01*
X896569Y206417D01*
X895902Y206684D01*
X895169Y207017D01*
X894169Y207550D01*
Y204884D01*
G01X897569Y209350D02*
X897902Y209750D01*
X898102Y210217D01*
X898169Y210817D01*
X898036Y211417D01*
X897769Y211884D01*
X897302Y212217D01*
X896769Y212284D01*
X896236Y212150D01*
X895902Y211817D01*
X895636Y211350D01*
X895569Y210884D01*
X895636Y210417D01*
X895902Y209817D01*
X894169Y210017D01*
Y211817D01*
G01X897369Y319950D02*
X897836Y320350D01*
X898102Y320884D01*
X898169Y321484D01*
X898102Y322017D01*
X897769Y322550D01*
X897369Y322884D01*
X896969Y322950D01*
X896502Y322817D01*
X896169Y322350D01*
X896036Y321884D01*
Y321284D01*
G01Y321884D02*
X895836Y322284D01*
X895502Y322617D01*
X895102Y322750D01*
X894702Y322617D01*
X894369Y322284D01*
X894169Y321684D01*
X894236Y321084D01*
X894502Y320484D01*
G01X894836Y324750D02*
X894436Y325150D01*
X894236Y325617D01*
X894169Y326150D01*
X894302Y326817D01*
X894636Y327284D01*
X895036Y327417D01*
X895436Y327350D01*
X895769Y327084D01*
X896436Y325750D01*
X896902Y325150D01*
X897569Y324750D01*
X898169Y324617D01*
Y327417D01*
G01Y329217D02*
X894169Y332017D01*
G01Y329217D02*
X898169Y332017D01*
G01Y335084D02*
X897302Y335217D01*
X896569Y335417D01*
X895902Y335684D01*
X895169Y336017D01*
X894169Y336550D01*
Y333884D01*
G01X897569Y338350D02*
X897902Y338750D01*
X898102Y339217D01*
X898169Y339817D01*
X898036Y340417D01*
X897769Y340884D01*
X897302Y341217D01*
X896769Y341284D01*
X896236Y341150D01*
X895902Y340817D01*
X895636Y340350D01*
X895569Y339884D01*
X895636Y339417D01*
X895902Y338817D01*
X894169Y339017D01*
Y340817D01*
G01X897369Y596462D02*
X897836Y596862D01*
X898102Y597396D01*
X898169Y597996D01*
X898102Y598529D01*
X897769Y599062D01*
X897369Y599396D01*
X896969Y599462D01*
X896502Y599329D01*
X896169Y598862D01*
X896036Y598396D01*
Y597796D01*
G01Y598396D02*
X895836Y598796D01*
X895502Y599129D01*
X895102Y599262D01*
X894702Y599129D01*
X894369Y598796D01*
X894169Y598196D01*
X894236Y597596D01*
X894502Y596996D01*
G01X894836Y601262D02*
X894436Y601662D01*
X894236Y602129D01*
X894169Y602662D01*
X894302Y603329D01*
X894636Y603796D01*
X895036Y603929D01*
X895436Y603862D01*
X895769Y603596D01*
X896436Y602262D01*
X896902Y601662D01*
X897569Y601262D01*
X898169Y601129D01*
Y603929D01*
G01Y605729D02*
X894169Y608529D01*
G01Y605729D02*
X898169Y608529D01*
G01Y611596D02*
X897302Y611729D01*
X896569Y611929D01*
X895902Y612196D01*
X895169Y612529D01*
X894169Y613062D01*
Y610396D01*
G01X897569Y614862D02*
X897902Y615262D01*
X898102Y615729D01*
X898169Y616329D01*
X898036Y616929D01*
X897769Y617396D01*
X897302Y617729D01*
X896769Y617796D01*
X896236Y617662D01*
X895902Y617329D01*
X895636Y616862D01*
X895569Y616396D01*
X895636Y615929D01*
X895902Y615329D01*
X894169Y615529D01*
Y617329D01*
G01X897369Y725462D02*
X897836Y725862D01*
X898102Y726396D01*
X898169Y726996D01*
X898102Y727529D01*
X897769Y728062D01*
X897369Y728396D01*
X896969Y728462D01*
X896502Y728329D01*
X896169Y727862D01*
X896036Y727396D01*
Y726796D01*
G01Y727396D02*
X895836Y727796D01*
X895502Y728129D01*
X895102Y728262D01*
X894702Y728129D01*
X894369Y727796D01*
X894169Y727196D01*
X894236Y726596D01*
X894502Y725996D01*
G01X894836Y730262D02*
X894436Y730662D01*
X894236Y731129D01*
X894169Y731662D01*
X894302Y732329D01*
X894636Y732796D01*
X895036Y732929D01*
X895436Y732862D01*
X895769Y732596D01*
X896436Y731262D01*
X896902Y730662D01*
X897569Y730262D01*
X898169Y730129D01*
Y732929D01*
G01Y734729D02*
X894169Y737529D01*
G01Y734729D02*
X898169Y737529D01*
G01Y740596D02*
X897302Y740729D01*
X896569Y740929D01*
X895902Y741196D01*
X895169Y741529D01*
X894169Y742062D01*
Y739396D01*
G01X897569Y743862D02*
X897902Y744262D01*
X898102Y744729D01*
X898169Y745329D01*
X898036Y745929D01*
X897769Y746396D01*
X897302Y746729D01*
X896769Y746796D01*
X896236Y746662D01*
X895902Y746329D01*
X895636Y745862D01*
X895569Y745396D01*
X895636Y744929D01*
X895902Y744329D01*
X894169Y744529D01*
Y746329D01*
G01X897369Y1001974D02*
X897836Y1002374D01*
X898102Y1002908D01*
X898169Y1003508D01*
X898102Y1004041D01*
X897769Y1004574D01*
X897369Y1004908D01*
X896969Y1004974D01*
X896502Y1004841D01*
X896169Y1004374D01*
X896036Y1003908D01*
Y1003308D01*
G01Y1003908D02*
X895836Y1004308D01*
X895502Y1004641D01*
X895102Y1004774D01*
X894702Y1004641D01*
X894369Y1004308D01*
X894169Y1003708D01*
X894236Y1003108D01*
X894502Y1002508D01*
G01X894836Y1006774D02*
X894436Y1007174D01*
X894236Y1007641D01*
X894169Y1008174D01*
X894302Y1008841D01*
X894636Y1009308D01*
X895036Y1009441D01*
X895436Y1009374D01*
X895769Y1009108D01*
X896436Y1007774D01*
X896902Y1007174D01*
X897569Y1006774D01*
X898169Y1006641D01*
Y1009441D01*
G01Y1011241D02*
X894169Y1014041D01*
G01Y1011241D02*
X898169Y1014041D01*
G01Y1017108D02*
X897302Y1017241D01*
X896569Y1017441D01*
X895902Y1017708D01*
X895169Y1018041D01*
X894169Y1018574D01*
Y1015908D01*
G01X897569Y1020374D02*
X897902Y1020774D01*
X898102Y1021241D01*
X898169Y1021841D01*
X898036Y1022441D01*
X897769Y1022908D01*
X897302Y1023241D01*
X896769Y1023308D01*
X896236Y1023174D01*
X895902Y1022841D01*
X895636Y1022374D01*
X895569Y1021908D01*
X895636Y1021441D01*
X895902Y1020841D01*
X894169Y1021041D01*
Y1022841D01*
G01X897369Y1130974D02*
X897836Y1131374D01*
X898102Y1131908D01*
X898169Y1132508D01*
X898102Y1133041D01*
X897769Y1133574D01*
X897369Y1133908D01*
X896969Y1133974D01*
X896502Y1133841D01*
X896169Y1133374D01*
X896036Y1132908D01*
Y1132308D01*
G01Y1132908D02*
X895836Y1133308D01*
X895502Y1133641D01*
X895102Y1133774D01*
X894702Y1133641D01*
X894369Y1133308D01*
X894169Y1132708D01*
X894236Y1132108D01*
X894502Y1131508D01*
G01X894836Y1135774D02*
X894436Y1136174D01*
X894236Y1136641D01*
X894169Y1137174D01*
X894302Y1137841D01*
X894636Y1138308D01*
X895036Y1138441D01*
X895436Y1138374D01*
X895769Y1138108D01*
X896436Y1136774D01*
X896902Y1136174D01*
X897569Y1135774D01*
X898169Y1135641D01*
Y1138441D01*
G01Y1140241D02*
X894169Y1143041D01*
G01Y1140241D02*
X898169Y1143041D01*
G01Y1146108D02*
X897302Y1146241D01*
X896569Y1146441D01*
X895902Y1146708D01*
X895169Y1147041D01*
X894169Y1147574D01*
Y1144908D01*
G01X897569Y1149374D02*
X897902Y1149774D01*
X898102Y1150241D01*
X898169Y1150841D01*
X898036Y1151441D01*
X897769Y1151908D01*
X897302Y1152241D01*
X896769Y1152308D01*
X896236Y1152174D01*
X895902Y1151841D01*
X895636Y1151374D01*
X895569Y1150908D01*
X895636Y1150441D01*
X895902Y1149841D01*
X894169Y1150041D01*
Y1151841D01*
G01X897369Y1407486D02*
X897836Y1407886D01*
X898102Y1408420D01*
X898169Y1409020D01*
X898102Y1409553D01*
X897769Y1410086D01*
X897369Y1410420D01*
X896969Y1410486D01*
X896502Y1410353D01*
X896169Y1409886D01*
X896036Y1409420D01*
Y1408820D01*
G01Y1409420D02*
X895836Y1409820D01*
X895502Y1410153D01*
X895102Y1410286D01*
X894702Y1410153D01*
X894369Y1409820D01*
X894169Y1409220D01*
X894236Y1408620D01*
X894502Y1408020D01*
G01X894836Y1412286D02*
X894436Y1412686D01*
X894236Y1413153D01*
X894169Y1413686D01*
X894302Y1414353D01*
X894636Y1414820D01*
X895036Y1414953D01*
X895436Y1414886D01*
X895769Y1414620D01*
X896436Y1413286D01*
X896902Y1412686D01*
X897569Y1412286D01*
X898169Y1412153D01*
Y1414953D01*
G01Y1416753D02*
X894169Y1419553D01*
G01Y1416753D02*
X898169Y1419553D01*
G01Y1422620D02*
X897302Y1422753D01*
X896569Y1422953D01*
X895902Y1423220D01*
X895169Y1423553D01*
X894169Y1424086D01*
Y1421420D01*
G01X897569Y1425886D02*
X897902Y1426286D01*
X898102Y1426753D01*
X898169Y1427353D01*
X898036Y1427953D01*
X897769Y1428420D01*
X897302Y1428753D01*
X896769Y1428820D01*
X896236Y1428686D01*
X895902Y1428353D01*
X895636Y1427886D01*
X895569Y1427420D01*
X895636Y1426953D01*
X895902Y1426353D01*
X894169Y1426553D01*
Y1428353D01*
G01X897369Y1536486D02*
X897836Y1536886D01*
X898102Y1537420D01*
X898169Y1538020D01*
X898102Y1538553D01*
X897769Y1539086D01*
X897369Y1539420D01*
X896969Y1539486D01*
X896502Y1539353D01*
X896169Y1538886D01*
X896036Y1538420D01*
Y1537820D01*
G01Y1538420D02*
X895836Y1538820D01*
X895502Y1539153D01*
X895102Y1539286D01*
X894702Y1539153D01*
X894369Y1538820D01*
X894169Y1538220D01*
X894236Y1537620D01*
X894502Y1537020D01*
G01X894836Y1541286D02*
X894436Y1541686D01*
X894236Y1542153D01*
X894169Y1542686D01*
X894302Y1543353D01*
X894636Y1543820D01*
X895036Y1543953D01*
X895436Y1543886D01*
X895769Y1543620D01*
X896436Y1542286D01*
X896902Y1541686D01*
X897569Y1541286D01*
X898169Y1541153D01*
Y1543953D01*
G01Y1545753D02*
X894169Y1548553D01*
G01Y1545753D02*
X898169Y1548553D01*
G01Y1551620D02*
X897302Y1551753D01*
X896569Y1551953D01*
X895902Y1552220D01*
X895169Y1552553D01*
X894169Y1553086D01*
Y1550420D01*
G01X897569Y1554886D02*
X897902Y1555286D01*
X898102Y1555753D01*
X898169Y1556353D01*
X898036Y1556953D01*
X897769Y1557420D01*
X897302Y1557753D01*
X896769Y1557820D01*
X896236Y1557686D01*
X895902Y1557353D01*
X895636Y1556886D01*
X895569Y1556420D01*
X895636Y1555953D01*
X895902Y1555353D01*
X894169Y1555553D01*
Y1557353D01*
G01X897369Y1812998D02*
X897836Y1813398D01*
X898102Y1813932D01*
X898169Y1814532D01*
X898102Y1815065D01*
X897769Y1815598D01*
X897369Y1815932D01*
X896969Y1815998D01*
X896502Y1815865D01*
X896169Y1815398D01*
X896036Y1814932D01*
Y1814332D01*
G01Y1814932D02*
X895836Y1815332D01*
X895502Y1815665D01*
X895102Y1815798D01*
X894702Y1815665D01*
X894369Y1815332D01*
X894169Y1814732D01*
X894236Y1814132D01*
X894502Y1813532D01*
G01X894836Y1817798D02*
X894436Y1818198D01*
X894236Y1818665D01*
X894169Y1819198D01*
X894302Y1819865D01*
X894636Y1820332D01*
X895036Y1820465D01*
X895436Y1820398D01*
X895769Y1820132D01*
X896436Y1818798D01*
X896902Y1818198D01*
X897569Y1817798D01*
X898169Y1817665D01*
Y1820465D01*
G01Y1822265D02*
X894169Y1825065D01*
G01Y1822265D02*
X898169Y1825065D01*
G01Y1828132D02*
X897302Y1828265D01*
X896569Y1828465D01*
X895902Y1828732D01*
X895169Y1829065D01*
X894169Y1829598D01*
Y1826932D01*
G01X897569Y1831398D02*
X897902Y1831798D01*
X898102Y1832265D01*
X898169Y1832865D01*
X898036Y1833465D01*
X897769Y1833932D01*
X897302Y1834265D01*
X896769Y1834332D01*
X896236Y1834198D01*
X895902Y1833865D01*
X895636Y1833398D01*
X895569Y1832932D01*
X895636Y1832465D01*
X895902Y1831865D01*
X894169Y1832065D01*
Y1833865D01*
G01X897369Y1941998D02*
X897836Y1942398D01*
X898102Y1942932D01*
X898169Y1943532D01*
X898102Y1944065D01*
X897769Y1944598D01*
X897369Y1944932D01*
X896969Y1944998D01*
X896502Y1944865D01*
X896169Y1944398D01*
X896036Y1943932D01*
Y1943332D01*
G01Y1943932D02*
X895836Y1944332D01*
X895502Y1944665D01*
X895102Y1944798D01*
X894702Y1944665D01*
X894369Y1944332D01*
X894169Y1943732D01*
X894236Y1943132D01*
X894502Y1942532D01*
G01X894836Y1946798D02*
X894436Y1947198D01*
X894236Y1947665D01*
X894169Y1948198D01*
X894302Y1948865D01*
X894636Y1949332D01*
X895036Y1949465D01*
X895436Y1949398D01*
X895769Y1949132D01*
X896436Y1947798D01*
X896902Y1947198D01*
X897569Y1946798D01*
X898169Y1946665D01*
Y1949465D01*
G01Y1951265D02*
X894169Y1954065D01*
G01Y1951265D02*
X898169Y1954065D01*
G01Y1957132D02*
X897302Y1957265D01*
X896569Y1957465D01*
X895902Y1957732D01*
X895169Y1958065D01*
X894169Y1958598D01*
Y1955932D01*
G01X897569Y1960398D02*
X897902Y1960798D01*
X898102Y1961265D01*
X898169Y1961865D01*
X898036Y1962465D01*
X897769Y1962932D01*
X897302Y1963265D01*
X896769Y1963332D01*
X896236Y1963198D01*
X895902Y1962865D01*
X895636Y1962398D01*
X895569Y1961932D01*
X895636Y1961465D01*
X895902Y1960865D01*
X894169Y1961065D01*
Y1962865D01*
G01X1033464Y1397976D02*
Y1424882D01*
X1029527Y1428819D01*
X1024212D01*
G02X1019291Y1433740I0J4921D01*
G01Y1610886D01*
X1018307Y1611870D01*
X989744D01*
G02Y1616082I0J2106D01*
G01X1018307D01*
X1019291Y1617066D01*
Y1676496D01*
G02X1024212Y1681417I4921J0D01*
G01X1029527D01*
X1033464Y1685354D01*
Y1712976D01*
G01X1038808Y1545726D02*
X1039141Y1546259D01*
X1039341Y1546859D01*
Y1547393D01*
X1039141Y1547926D01*
X1038808Y1548326D01*
X1038341Y1548526D01*
X1037874Y1548393D01*
X1037474Y1548059D01*
X1037208Y1547459D01*
X1037074Y1546659D01*
X1036808Y1546193D01*
X1036341Y1545993D01*
X1035874Y1546126D01*
X1035541Y1546459D01*
X1035341Y1546926D01*
Y1547393D01*
X1035474Y1547859D01*
X1035808Y1548259D01*
G01X1039341Y1551726D02*
X1035341D01*
G01X1036674Y1556326D02*
X1039341D01*
G01X1035608D02*
X1035541Y1556193D01*
X1035408D01*
X1035341Y1556326D01*
X1035408Y1556459D01*
X1035541D01*
X1035608Y1556326D01*
G01X1035341Y1560926D02*
X1039341D01*
G01X1036674Y1559993D02*
Y1561859D01*
G01X1019816Y1553876D02*
X1035791Y1553976D01*
G01X1024807Y1555407D02*
X1019816Y1553876D01*
X1024825Y1552407D01*
X1024807Y1555407D01*
G54D11*
X11999Y53550D03*
X11499Y34050D03*
X10000Y16500D03*
X11499Y142050D03*
X11999Y69050D03*
X6891Y161611D03*
X11302Y161500D03*
X7089Y166111D03*
X11500Y166000D03*
X9499Y301050D03*
Y281550D03*
X8999Y318550D03*
X8599Y751650D03*
X10999Y774050D03*
X8999Y889550D03*
X8499Y979050D03*
X8999Y961550D03*
Y942050D03*
Y926550D03*
X8499Y907050D03*
X8999Y1060550D03*
Y1041050D03*
Y1025550D03*
X8499Y1006050D03*
X8999Y988550D03*
X6500Y1098000D03*
Y1103500D03*
Y1110000D03*
Y1116500D03*
X8499Y1078050D03*
X6500Y1146000D03*
X13000Y1145500D03*
Y1151000D03*
X7000Y1151500D03*
X8799Y1302550D03*
X7499Y1282050D03*
X7999Y1264550D03*
X9399Y1347350D03*
X8299Y1320050D03*
X7099Y1717750D03*
X7199Y1731450D03*
X6099Y1753750D03*
X11299Y1850050D03*
X9099Y1881550D03*
X8499Y1979550D03*
X11500Y1987000D03*
X92999Y52050D03*
X90899Y14850D03*
X23499Y27050D03*
X50999Y21150D03*
Y47750D03*
X27799Y38450D03*
X25799Y64050D03*
X65499Y59050D03*
Y41550D03*
Y27050D03*
X40999Y42050D03*
Y27550D03*
X17600Y5604D03*
X36000D03*
X55700Y5900D03*
X73900Y6200D03*
X90900Y5800D03*
X88000Y36400D03*
X93000Y44900D03*
X92900Y39700D03*
X32400Y115400D03*
X37000Y115300D03*
X32300Y121000D03*
X36900Y120900D03*
X32100Y130700D03*
X37000D03*
X32100Y136600D03*
X36800Y136700D03*
X52499Y145050D03*
Y130550D03*
X59499Y108050D03*
Y90550D03*
Y76050D03*
X96184Y151065D03*
X71015Y123666D03*
X78165Y137116D03*
X95814Y136065D03*
X77165Y110799D03*
X36500Y179000D03*
Y188500D03*
X35000Y198500D03*
X30000Y179000D03*
X23500D03*
X30000Y188500D03*
X24000D03*
X29000Y198000D03*
X23500D03*
X15302Y161500D03*
X19500D03*
X15500Y166000D03*
X19198Y152000D03*
X19698Y166000D03*
X92899Y231450D03*
X48499Y228550D03*
X23999Y229050D03*
X52499Y162550D03*
X96184Y166065D03*
X23895Y238995D03*
X51099Y300050D03*
X90899Y309550D03*
X93199Y279650D03*
X84899Y289250D03*
X86899Y242750D03*
X75299Y261750D03*
X42999Y275650D03*
X48499Y260550D03*
Y243050D03*
X23999Y261050D03*
Y243550D03*
X52199Y342350D03*
X89899Y368350D03*
X94199Y325550D03*
X93499Y337450D03*
X95499Y355450D03*
X89999Y396450D03*
X39999Y359550D03*
Y342050D03*
Y327550D03*
X15499Y360050D03*
Y342550D03*
Y328050D03*
X94500Y456800D03*
X75300Y454100D03*
X67300Y450200D03*
X68899Y445450D03*
X87599Y403950D03*
X76099Y414250D03*
X95399Y416350D03*
X89099Y426150D03*
X93499Y481550D03*
Y477050D03*
X93199Y449850D03*
X93500Y445300D03*
X42299Y564150D03*
X62055Y561550D03*
X49555Y563550D03*
X75999Y556640D03*
X70800Y540300D03*
X77165Y514650D03*
X94499Y486550D03*
X52333Y641295D03*
X72599Y578236D03*
X39999Y576550D03*
X61099Y603236D03*
X93599Y581236D03*
X92599Y606236D03*
X93100Y571640D03*
X44000Y728500D03*
X40000Y729000D03*
X47800Y692800D03*
X53210Y701486D03*
X43499Y657550D03*
X44500Y733000D03*
X40000D03*
X43999Y737550D03*
X39999Y738050D03*
X44499Y742050D03*
X39999D03*
X39899Y754850D03*
X39399Y768750D03*
X27199Y764950D03*
X28599Y775450D03*
X26399Y750850D03*
X14799Y751450D03*
X17299Y773950D03*
X79900Y791300D03*
X67999Y790400D03*
X53999Y791000D03*
X93299Y862050D03*
X26799Y874550D03*
X26099Y891650D03*
X76399Y820450D03*
X70100Y818900D03*
X93690Y887139D03*
X93900Y882400D03*
X94001Y856895D03*
X93808Y852063D03*
X93499Y892050D03*
X25699Y916150D03*
X25099Y942150D03*
X23899Y957950D03*
X93499Y897152D03*
X93000Y907165D03*
X77499Y921550D03*
X77002Y952079D03*
X76711Y948089D03*
X77499Y962152D03*
X83988Y934028D03*
X24799Y992250D03*
X33899Y1005950D03*
X65799Y994050D03*
X72799Y982950D03*
X86900Y981600D03*
X67000Y1011500D03*
X21500Y1122500D03*
Y1092500D03*
X17500D03*
X22500Y1183000D03*
Y1176500D03*
Y1170000D03*
Y1164500D03*
X18000Y1145500D03*
X17500Y1150500D03*
X22447Y1223247D03*
X23200Y1209300D03*
X21299Y1300250D03*
X21799Y1282750D03*
X22321Y1231121D03*
X18099Y1343550D03*
X96000Y1369000D03*
X96100Y1384650D03*
X77166Y1353400D03*
X93316Y1351000D03*
X77165Y1327335D03*
X76499Y1507050D03*
Y1498050D03*
Y1512050D03*
Y1503050D03*
X76999Y1528050D03*
Y1519050D03*
X83499Y1602050D03*
X92499Y1589050D03*
X86999D03*
X83499Y1594050D03*
Y1598050D03*
X74999Y1602050D03*
X78999D03*
X81499Y1589050D03*
X78999Y1593550D03*
X74999Y1598050D03*
Y1593550D03*
X78999Y1598050D03*
X90999Y1628550D03*
Y1624550D03*
X91121Y1632549D03*
X86299Y1632550D03*
X85999Y1628550D03*
Y1624550D03*
X15299Y1723450D03*
X15399Y1708350D03*
X14899Y1736250D03*
X15299Y1753250D03*
X84099Y1737150D03*
X83599Y1744750D03*
X77165Y1759550D03*
X93499D03*
X94336Y1773113D03*
X78529Y1788113D03*
X38600Y1880200D03*
X31400Y1885200D03*
X30400Y1849650D03*
X23999Y1857950D03*
X27199Y1874350D03*
X52999Y1871550D03*
X57499Y1871050D03*
X82999Y1887550D03*
X78999D03*
X36100Y1892200D03*
X58999Y1958050D03*
X82499Y1957050D03*
X73499D03*
X66499D03*
X92499Y1959050D03*
X47499Y1915050D03*
X62999Y1914550D03*
Y1926050D03*
X81499Y1915550D03*
X47499Y1930550D03*
X62499Y1939550D03*
X73499Y1945550D03*
X83999Y1945050D03*
X78999Y1891550D03*
X82999D03*
X78999Y1896050D03*
X78433Y1900010D03*
X78999Y1904050D03*
X83499Y1896050D03*
X83433Y1904010D03*
X83999Y1900050D03*
X79500Y1987500D03*
X61500D03*
X44500Y1987000D03*
X26500D03*
X55999Y1982550D03*
X96999Y49550D03*
X157299Y5150D03*
X107000Y6000D03*
X97800Y36000D03*
X96900Y40400D03*
X167499Y43550D03*
X116400Y56000D03*
X129100Y55900D03*
X127499Y65050D03*
X141999Y65550D03*
X156499Y66050D03*
X169300Y130300D03*
X178700Y129900D03*
X152999Y141050D03*
X123499Y149050D03*
X133999D03*
X142999Y141050D03*
X132999Y141550D03*
X176499Y140050D03*
X167499Y149550D03*
X144499Y149050D03*
X163499Y140050D03*
X160999Y149550D03*
X123499Y140050D03*
X129999Y78050D03*
X166999Y88050D03*
X166499Y83550D03*
Y79050D03*
X158499D03*
Y84050D03*
Y88550D03*
Y93550D03*
X166999Y92550D03*
Y97050D03*
X127999Y99550D03*
X165499Y106050D03*
X169999Y103050D03*
X114800Y68500D03*
X177899Y199250D03*
X117500Y162300D03*
X124300Y167800D03*
X131799Y201950D03*
X142688Y218861D03*
X143110Y203861D03*
X97999Y199050D03*
X155999Y181050D03*
X135399Y277050D03*
X130799Y300250D03*
X158999Y259800D03*
X152808Y246341D03*
X166800Y240800D03*
X133000Y240500D03*
X157740Y273924D03*
X139399Y372350D03*
X167299Y369350D03*
X130099Y326150D03*
X134699Y356050D03*
X126099Y396150D03*
X152499Y395950D03*
X137100Y436800D03*
X129400Y426900D03*
X135999Y472550D03*
X135140Y478930D03*
X100500Y456700D03*
X99399Y437450D03*
X124899Y409050D03*
X133499Y445050D03*
X128999Y445550D03*
X130000Y452000D03*
X97699Y477050D03*
Y481550D03*
X149700Y471600D03*
X154100Y476500D03*
X164600Y476700D03*
X171300D03*
X97999Y445550D03*
X97699Y449850D03*
X147300Y526700D03*
X147590Y521500D03*
X108599Y557236D03*
X154099Y529236D03*
X101500Y536500D03*
X139200Y484300D03*
X134499Y488050D03*
X145649Y509550D03*
X136349Y509050D03*
X98999Y488050D03*
X140499Y499050D03*
X153499Y502550D03*
X148999D03*
X136299Y499050D03*
X108900Y587600D03*
X162500Y623400D03*
X140000Y587700D03*
X140499Y600550D03*
X152400Y643300D03*
X140499Y626050D03*
X143999Y605550D03*
X170799Y689150D03*
X171999Y672450D03*
X131099Y700450D03*
X139099Y707150D03*
X152124Y651868D03*
X159054Y665400D03*
X152499Y810550D03*
X110800Y772700D03*
X178899Y765250D03*
X172599Y774250D03*
X161999Y768050D03*
X152499Y816050D03*
Y820550D03*
Y825050D03*
X156499Y876050D03*
Y870550D03*
X97499Y862050D03*
X111299Y821050D03*
X172099Y877450D03*
X168499Y846713D03*
X173899Y846550D03*
X161999Y843550D03*
Y848050D03*
X156499Y846050D03*
X156999Y850050D03*
X158114Y883290D03*
X156499Y886950D03*
X155499Y891050D03*
Y896050D03*
X97700Y887400D03*
X97900Y882400D03*
X163999Y863050D03*
X159999D03*
X155999Y859050D03*
Y863050D03*
X97800Y851800D03*
X98001Y856950D03*
X97499Y892550D03*
X151999Y936550D03*
X152499Y931550D03*
X109500Y901100D03*
X153299Y943750D03*
X106500Y943000D03*
X105300Y960300D03*
X169299Y956350D03*
X159459Y896616D03*
X163499Y896550D03*
X157499Y909050D03*
Y904550D03*
X159186Y946117D03*
X151300Y1049300D03*
X171499Y998650D03*
X156499Y985950D03*
X149499Y997650D03*
X162499Y1023550D03*
X163499Y1035050D03*
X158300Y1015000D03*
X141234Y1029885D03*
X140864Y1044885D03*
X159499Y1044579D03*
X165600Y1057428D03*
X100999Y1099550D03*
X105000Y1100500D03*
X100999Y1095050D03*
X105006Y1095366D03*
X110999Y1130550D03*
X115200Y1130300D03*
X110999Y1126050D03*
Y1122050D03*
Y1118050D03*
X114999Y1126050D03*
Y1122050D03*
Y1118050D03*
X137900Y1103400D03*
X139100Y1097100D03*
X169299Y1067150D03*
X168099Y1083550D03*
X167999Y1092850D03*
X143200Y1116300D03*
X134500Y1108100D03*
X171599Y1139950D03*
X167499Y1118550D03*
X167999Y1130550D03*
X133200Y1132100D03*
X164999Y1075550D03*
X159055Y1070400D03*
X106999Y1114960D03*
X144149Y1226113D03*
Y1222113D03*
X148499D03*
Y1226113D03*
X145900Y1163200D03*
X163499Y1171650D03*
X151699Y1158550D03*
X144399Y1171150D03*
X150999Y1181150D03*
X141499Y1185550D03*
X151499Y1173050D03*
X121657Y1224604D03*
X120999Y1188050D03*
X111999D03*
X102999D03*
X128400Y1188600D03*
X144149Y1230113D03*
X148486D03*
X104999Y1231050D03*
X100999Y1231032D03*
X120999Y1228550D03*
X120499Y1264550D03*
X126499D03*
X123938Y1267623D03*
X103499Y1305050D03*
X117149Y1267550D03*
X175823Y1297070D03*
X175499Y1302113D03*
Y1306113D03*
Y1292550D03*
X145999Y1353050D03*
X167499Y1389050D03*
X123500Y1360300D03*
X156999Y1397750D03*
X143199Y1412050D03*
X163499Y1433350D03*
X166799Y1409350D03*
X178200Y1393400D03*
X176599Y1447450D03*
X172299Y1465850D03*
X165499Y1453550D03*
X157915Y1420460D03*
X140799Y1435460D03*
X166799Y1487450D03*
X176299Y1500150D03*
X159054Y1476200D03*
X124999Y1616050D03*
Y1620050D03*
Y1629050D03*
Y1633050D03*
X119999Y1629050D03*
X120100Y1633100D03*
X105749Y1712749D03*
X122499Y1668550D03*
Y1672550D03*
X126562Y1670613D03*
X118999Y1670550D03*
X172499Y1714050D03*
X167499Y1714113D03*
X162499D03*
X130499Y1730050D03*
X128000Y1735000D03*
X144499Y1729550D03*
X139500Y1730500D03*
X133000Y1734500D03*
X157500Y1797400D03*
X126599Y1789650D03*
X120299Y1796150D03*
X142144Y1801644D03*
X104417Y1791480D03*
X144499Y1745550D03*
X137999Y1747723D03*
X129999Y1747050D03*
X123499D03*
X117499Y1745050D03*
X170499Y1731050D03*
X165499Y1730613D03*
X172499Y1726613D03*
X167999D03*
X163499D03*
X97999Y1815050D03*
X104500Y1813400D03*
X173899Y1813250D03*
X177599Y1866750D03*
X168299Y1879850D03*
X168499Y1855550D03*
X127499Y1889050D03*
X126999Y1882550D03*
X111499Y1877550D03*
Y1882550D03*
X122999Y1883050D03*
X115999Y1882550D03*
X157999Y1840972D03*
X158000Y1825400D03*
X159054Y1881800D03*
X167200Y1868000D03*
X159054Y1855050D03*
X143491Y1856400D03*
X116499Y1877550D03*
X122999Y1889050D03*
X132700Y1972400D03*
X137900Y1972200D03*
X126500Y1972400D03*
X168899Y1960750D03*
X163599Y1892050D03*
X159173Y1935972D03*
X142499Y1905972D03*
X141499Y1895972D03*
X131100Y1908500D03*
X129600Y1912400D03*
X124433Y1908510D03*
X124999Y1912550D03*
X98433Y1940510D03*
X98999Y1944550D03*
X102433Y1940555D03*
X103433Y1944510D03*
X132700Y1978600D03*
X137900Y1978400D03*
X126600Y1978500D03*
X119999Y1978550D03*
X119499Y1972550D03*
X98000Y1987500D03*
X163500D03*
X146000D03*
X128500D03*
X115000Y1987000D03*
X189499Y39150D03*
X197999Y39900D03*
X193999D03*
X208499Y45650D03*
X199999Y46050D03*
X194499Y44050D03*
X246200Y65800D03*
X246000Y61300D03*
Y56500D03*
Y52100D03*
X245600Y43800D03*
X245500Y39100D03*
X247100Y47900D03*
X189499Y4550D03*
X206999Y5050D03*
X226499D03*
X241999D03*
X261499Y4550D03*
X225499Y52550D03*
Y46550D03*
Y63550D03*
Y58050D03*
X183499Y45550D03*
X192499Y57550D03*
X246000Y70800D03*
X244900Y149100D03*
X244499Y136550D03*
Y122050D03*
X229099Y161350D03*
X206899Y171650D03*
X190199Y178650D03*
X232400Y220700D03*
X210999Y221550D03*
X191999D03*
X227499Y192050D03*
X231999D03*
X227999Y187050D03*
X231999D03*
X227999Y182550D03*
X231999D03*
X227999Y178050D03*
X231999D03*
X249800Y248800D03*
X235399Y263350D03*
X201199Y266750D03*
X181299Y267350D03*
X217999Y250550D03*
X203499D03*
X185999D03*
X187199Y359050D03*
X223799Y365350D03*
X209199Y365050D03*
X181599Y396250D03*
X217599Y396450D03*
X258999Y396650D03*
X179999Y442550D03*
X179649Y438550D03*
X183999D03*
Y442550D03*
Y447050D03*
X179999D03*
X209999Y426150D03*
X237699Y426050D03*
X218499Y474850D03*
X251499Y446050D03*
X231999Y445550D03*
X251999Y462050D03*
X232499Y461550D03*
X209499Y412550D03*
X220000Y421000D03*
X232999Y414550D03*
X252499Y415050D03*
X194999Y490050D03*
X190499Y487550D03*
X191199Y491550D03*
X244199Y483350D03*
X224299Y494650D03*
X242099Y511750D03*
X244999Y559550D03*
Y545050D03*
X220499Y560050D03*
Y545550D03*
X257499Y530050D03*
Y512550D03*
Y498050D03*
X205300Y508100D03*
X190499Y507513D03*
X187499Y531613D03*
Y536113D03*
X193499Y541113D03*
X188999D03*
X193499Y549613D03*
X188999D03*
Y545613D03*
X193999Y545550D03*
X257199Y640050D03*
X224999Y613450D03*
X256499Y609050D03*
Y591550D03*
Y577050D03*
X245000Y647000D03*
X244499Y632050D03*
X219999Y647050D03*
Y632550D03*
X207300Y639400D03*
X206499Y623550D03*
Y609050D03*
X181999Y641550D03*
Y624050D03*
Y609550D03*
X244999Y577050D03*
X220499Y577550D03*
X199199Y659150D03*
X234200Y668300D03*
X226399Y677550D03*
X212999Y677350D03*
X190399Y689050D03*
X182599Y688350D03*
X246500Y663300D03*
X218800Y668700D03*
X224099Y770250D03*
X209500Y759000D03*
X208799Y766750D03*
X214799Y774750D03*
X245599Y773450D03*
X234299Y773750D03*
X247099Y795050D03*
X227199D03*
X197099D03*
X254699Y807650D03*
X233799Y806350D03*
X208299Y805350D03*
X198199Y805950D03*
X190699Y778350D03*
X215999Y887550D03*
X220499D03*
X215499Y883550D03*
X204496Y846111D03*
X204649Y838050D03*
X208999D03*
X209000Y846113D03*
X204649Y842113D03*
X208986D03*
X244099Y857450D03*
X245199Y878050D03*
X232399Y886550D03*
X252899Y886350D03*
X252399Y838250D03*
X245399Y823550D03*
X217300Y816800D03*
X198499Y884113D03*
X245399Y907450D03*
X243899Y923650D03*
X242199Y938750D03*
X256199Y916250D03*
X254899Y929250D03*
X253499Y938050D03*
X252499Y948850D03*
X244199Y973250D03*
X225299Y957650D03*
X213999Y958650D03*
X206699Y953050D03*
X203999Y943350D03*
X204699Y929450D03*
X205999Y978250D03*
X256499Y967050D03*
X233499Y966050D03*
X216999Y967550D03*
X219499Y939613D03*
Y948613D03*
Y943813D03*
X214999Y939613D03*
Y944113D03*
Y948613D03*
X219499Y926613D03*
X214999D03*
X254499Y984550D03*
X245899Y995250D03*
X232299Y981950D03*
X206299Y990250D03*
X207299Y1008150D03*
X202100Y1028100D03*
X253999Y1052050D03*
X253499Y1038550D03*
X232499Y1038050D03*
X216499Y1053050D03*
X215999Y1039550D03*
X258999Y1011550D03*
X233999Y1012550D03*
Y997050D03*
X217999Y1012050D03*
X217499Y998550D03*
Y981050D03*
X199499Y1093850D03*
X209900Y1093600D03*
X249499Y1104150D03*
X260349Y1139200D03*
X214499Y1154250D03*
X223099Y1182750D03*
X210199Y1173450D03*
X204199Y1163850D03*
X208199Y1145850D03*
X180400Y1202800D03*
X201600Y1205900D03*
X220999Y1224350D03*
X242199Y1210050D03*
X242599Y1198350D03*
X232599Y1195750D03*
X247899Y1208650D03*
X251999Y1184550D03*
X212499Y1212550D03*
X181700Y1219900D03*
X212499Y1184550D03*
X196499Y1224550D03*
Y1215550D03*
Y1196550D03*
X259999Y1152992D03*
X259499Y1161550D03*
X202199Y1276850D03*
X202899Y1291450D03*
X179500Y1262000D03*
X179800Y1244100D03*
X196399Y1236650D03*
X221599Y1237250D03*
X222299Y1251850D03*
X229899Y1250550D03*
X216300Y1274800D03*
X234299Y1232650D03*
X261199Y1227950D03*
X250900Y1248500D03*
X242900Y1263000D03*
X232799Y1276150D03*
X254899Y1289950D03*
X241399Y1303250D03*
X211499Y1267050D03*
Y1258050D03*
Y1239050D03*
X195499Y1279050D03*
Y1270050D03*
Y1251050D03*
X179999Y1306050D03*
Y1301550D03*
Y1292550D03*
Y1296613D03*
X239099Y1314150D03*
X252399Y1326350D03*
X219099Y1325950D03*
X226599Y1340250D03*
X207699Y1337950D03*
X195500Y1352500D03*
X213199Y1350050D03*
X227399Y1363050D03*
X234300Y1375700D03*
X217499Y1387450D03*
X249800Y1388400D03*
X245999Y1358050D03*
X246499Y1370050D03*
X245999Y1339050D03*
X208049Y1385550D03*
X258999Y1396950D03*
X230599Y1400250D03*
X217999Y1408850D03*
X204699Y1418350D03*
X203199Y1393250D03*
X201000Y1408500D03*
X180599Y1424050D03*
X180000Y1439500D03*
X204999Y1472650D03*
X250199Y1473550D03*
X226300Y1447800D03*
X230899Y1437350D03*
X238899Y1453750D03*
X259299Y1438750D03*
X227999Y1421550D03*
X212400Y1433700D03*
X194200Y1457900D03*
X244999Y1412550D03*
X245499Y1424550D03*
X181500Y1479000D03*
X202399Y1500750D03*
X208999Y1491250D03*
X247500Y1499000D03*
X248000Y1482000D03*
X212899Y1535550D03*
X230999D03*
X213399Y1500300D03*
X236999Y1535550D03*
X260999Y1503550D03*
X180299Y1626550D03*
X180000Y1619600D03*
X195700Y1619100D03*
X195600Y1623700D03*
X180299Y1634550D03*
X179733Y1630590D03*
X246200Y1617600D03*
X239400Y1624300D03*
X218000Y1614300D03*
X209200Y1624000D03*
X228999Y1637550D03*
X211999Y1568550D03*
X238300Y1575100D03*
X231499Y1575050D03*
X224499D03*
X217999Y1574550D03*
X211999D03*
X258700Y1645100D03*
X237400Y1663800D03*
X230600Y1670500D03*
X197600Y1694900D03*
X204400Y1688200D03*
X216601Y1684350D03*
X226800Y1684200D03*
X220100Y1691700D03*
X209901Y1691850D03*
X212000Y1701300D03*
X201801Y1701450D03*
X195001Y1708150D03*
X205200Y1708000D03*
X180701Y1716050D03*
X195500Y1717000D03*
X200600Y1663600D03*
X199900Y1670600D03*
X213000Y1672500D03*
X181900Y1675300D03*
X255699Y1722550D03*
X222700Y1710100D03*
X242999Y1658050D03*
X193499Y1674050D03*
X253999Y1676550D03*
X235499Y1697050D03*
X256499Y1710050D03*
X180000Y1731000D03*
X179701Y1724550D03*
X195000Y1725500D03*
X249199Y1743150D03*
X222499Y1743850D03*
X259499Y1760650D03*
X221499Y1760950D03*
X199699Y1761450D03*
X220799Y1791550D03*
X252199Y1793050D03*
X238699Y1801850D03*
X205199Y1801950D03*
X182299Y1801350D03*
X206900Y1726700D03*
X185999Y1746050D03*
X237999Y1730550D03*
X244999Y1755050D03*
X253899Y1813250D03*
X215299Y1813950D03*
X255999Y1855950D03*
X204399Y1855450D03*
X206999Y1867550D03*
X241199Y1867150D03*
X244700Y1878700D03*
X224800Y1867000D03*
X212399Y1885850D03*
X199599Y1879850D03*
X181099Y1885850D03*
X261499Y1825050D03*
X209999D03*
X192100Y1813500D03*
X228999Y1856050D03*
X226999Y1941050D03*
X241255Y1896055D03*
X205499Y1968650D03*
X183999Y1968150D03*
X190399Y1961250D03*
X207199Y1892850D03*
X191599Y1891550D03*
X238999Y1970550D03*
X232999Y1971050D03*
X227499D03*
X221300Y1971200D03*
X240900Y1979000D03*
X225199Y1978750D03*
X209699D03*
X188199Y1978250D03*
X254500Y1987500D03*
X236500D03*
X216999Y1987550D03*
X199000Y1987500D03*
X183000D03*
X199600Y1974900D03*
X289499Y39050D03*
X286603Y34928D03*
X278999Y5050D03*
X292999Y4550D03*
X310499Y5050D03*
X329999D03*
X306999Y55450D03*
X311299D03*
X315799Y55350D03*
X290999Y67550D03*
X300700Y39400D03*
X304500Y44500D03*
X305100Y39700D03*
X294100Y28000D03*
X308900Y41000D03*
X308800Y46400D03*
X306100Y126500D03*
X332200Y94200D03*
X283599Y106250D03*
X274700Y131500D03*
X280999Y120050D03*
X289999Y72550D03*
X288499Y76550D03*
X289499Y80550D03*
X308499Y72550D03*
X303999Y74050D03*
X307999Y78550D03*
X343799Y204550D03*
X321799Y173950D03*
X343399Y161350D03*
X307199Y205550D03*
X317499Y192950D03*
X331499Y193250D03*
X262699Y208550D03*
X262299Y164050D03*
X280999Y152050D03*
X343999Y190050D03*
X337999Y219050D03*
X310499Y216550D03*
X290999Y216050D03*
X271999D03*
X325499Y249450D03*
X313199Y270350D03*
X297999Y245050D03*
X283499D03*
X265999D03*
X343499Y253550D03*
X337499Y282550D03*
X313000Y313900D03*
X316999Y312576D03*
X279998Y308614D03*
Y304114D03*
Y299614D03*
Y295114D03*
X267498Y310114D03*
Y305114D03*
Y300114D03*
Y295114D03*
X305998Y352114D03*
X293998Y361114D03*
Y356614D03*
Y352114D03*
X289998Y361114D03*
Y356614D03*
Y352114D03*
X276299Y376050D03*
X299899Y376650D03*
X328799Y372350D03*
X339399Y358050D03*
X289399Y395750D03*
X310999Y396250D03*
X338399Y395650D03*
X321748Y343299D03*
X277799Y338599D03*
X266699Y425050D03*
X336099Y417550D03*
X322099Y426850D03*
X338899Y433850D03*
X300899Y431850D03*
X328599Y442250D03*
X291599Y446150D03*
X266199Y472350D03*
X327900Y463200D03*
X306100Y462000D03*
X286999Y462050D03*
X272499Y445050D03*
X272999Y461050D03*
X269999Y415050D03*
X284499D03*
X303999Y415550D03*
X324999Y414550D03*
X277999Y545350D03*
X329999Y510450D03*
X298599Y501250D03*
X309399Y513450D03*
X321999Y533150D03*
X297599Y519350D03*
X340799Y512050D03*
X341399Y535850D03*
Y558950D03*
X331999Y555050D03*
Y540550D03*
X307499Y555550D03*
Y541050D03*
X281999Y529550D03*
Y512050D03*
Y497550D03*
X321999Y550550D03*
X297499Y551050D03*
X333499Y483050D03*
X312499Y484050D03*
X292999Y483550D03*
X321299Y565250D03*
X296199Y568550D03*
X320799Y582050D03*
X340299Y586550D03*
X342199Y613050D03*
X328599Y602450D03*
X302899Y607950D03*
X328499Y635650D03*
X317999Y627850D03*
X342099Y646350D03*
X280999Y608550D03*
Y591050D03*
Y576550D03*
X331999Y572550D03*
X307499Y573050D03*
X331999Y646550D03*
X307499Y647050D03*
X293999Y630550D03*
Y616050D03*
X269499Y631050D03*
Y616550D03*
X341899Y664950D03*
X342599Y678850D03*
X341399Y715050D03*
X330799Y712450D03*
X324599Y696150D03*
X297699Y681850D03*
X296399Y716950D03*
X308899Y705150D03*
X298399Y703450D03*
X331999Y678550D03*
Y661050D03*
X307499Y679050D03*
Y661550D03*
X293999Y648050D03*
X269499Y648550D03*
X268499Y716550D03*
Y711550D03*
Y701550D03*
Y706550D03*
X280999Y717550D03*
X280433Y713590D03*
X280999Y701550D03*
Y705550D03*
X294999Y767050D03*
X290999D03*
X294999Y762550D03*
Y758050D03*
X290999Y762550D03*
Y758050D03*
X306999D03*
X338099Y811650D03*
X307999Y803150D03*
X307899Y794550D03*
X287799Y794850D03*
X268099Y795450D03*
X275299Y806350D03*
X315000Y754500D03*
X338599Y821650D03*
X318999Y814350D03*
X338599Y840450D03*
X325599Y823950D03*
X283599Y857450D03*
X293899Y843850D03*
X304899Y856150D03*
X315199Y869450D03*
X323099Y885050D03*
X340099Y887350D03*
X330299Y871850D03*
X323799Y859850D03*
X313499Y847850D03*
X300199Y835250D03*
X288899Y820550D03*
X264999Y858450D03*
X280999Y843050D03*
Y827550D03*
X264999Y842550D03*
X264499Y829050D03*
X297499Y884050D03*
Y868550D03*
X281499Y883550D03*
X280999Y870050D03*
X265799Y901850D03*
X274299Y912950D03*
X310699Y943550D03*
X323499Y956950D03*
X329799Y970650D03*
X331099Y923650D03*
X322099Y913650D03*
X302499Y899050D03*
X321099Y899650D03*
X338399Y901050D03*
X340099Y910350D03*
X340399Y931250D03*
X340099Y952850D03*
X328099Y937250D03*
X315199Y925950D03*
X302199Y914650D03*
X287299Y901050D03*
X269599Y923950D03*
X267199Y935350D03*
X264799Y946850D03*
X263299Y959350D03*
X281099Y943550D03*
X278799Y956150D03*
X277599Y975250D03*
X290099Y948650D03*
X289399Y963350D03*
X288099Y971250D03*
X299399Y965950D03*
X298099Y977250D03*
X307999Y970650D03*
X272999Y965550D03*
X333099Y983450D03*
X285399Y982950D03*
X294699Y989550D03*
X306699Y981250D03*
X304399Y997550D03*
X320999Y997250D03*
X331299Y1017150D03*
X331599Y1028750D03*
X329599Y1040750D03*
X321299Y1012450D03*
Y1024750D03*
X318299Y1038750D03*
X329599Y1057050D03*
X317699Y1054650D03*
X299999Y1052350D03*
X289699Y1021750D03*
X298399Y1008150D03*
X287099Y1000150D03*
X306399Y1020750D03*
X303699Y1038050D03*
X304699Y1057050D03*
X287099Y1035050D03*
X275099Y1024750D03*
X262499Y995850D03*
X269999Y1052550D03*
Y1037050D03*
X274999Y1012050D03*
Y996550D03*
X272999Y981050D03*
X339599Y1081550D03*
X319999Y1066950D03*
X274900Y1115600D03*
X262499Y1129150D03*
X272999Y1102850D03*
X312299Y1093550D03*
X276299Y1134550D03*
X290699Y1122650D03*
X329299Y1098550D03*
X326599Y1112350D03*
X307999Y1142050D03*
X299499Y1113550D03*
Y1098050D03*
X283499Y1113050D03*
X282999Y1099550D03*
X332999Y1138550D03*
Y1123050D03*
X317999Y1137550D03*
X316499Y1124550D03*
X283299Y1144850D03*
X323999Y1153250D03*
X304499Y1156650D03*
X313499Y1170150D03*
X291399Y1174150D03*
X300699Y1185150D03*
X279799Y1191750D03*
X286599Y1203750D03*
X315408Y1202663D03*
X329799Y1182750D03*
X311999Y1213850D03*
X300699Y1227350D03*
X272999Y1214150D03*
X326649Y1218850D03*
X328999Y1200550D03*
X272499Y1153050D03*
X268499D03*
X263999D03*
X271999Y1161550D03*
X267999D03*
X263499D03*
X333349Y1307000D03*
X310299Y1240050D03*
X264800Y1261300D03*
X283799Y1249250D03*
X304699Y1265850D03*
X312499Y1280350D03*
X300499Y1305350D03*
X274299Y1276450D03*
X295399Y1292950D03*
X281099Y1302850D03*
X333349Y1288900D03*
Y1270500D03*
X327999Y1255050D03*
X326649Y1227850D03*
X333349Y1332800D03*
X311500Y1316300D03*
X264799Y1313850D03*
X286799Y1326450D03*
X297899Y1336150D03*
X298099Y1357250D03*
X265299Y1339650D03*
X263699Y1359550D03*
X301699Y1377950D03*
X278799Y1386250D03*
X265499Y1376950D03*
X343599Y1360050D03*
X344399Y1338150D03*
X313600Y1391300D03*
X312900Y1366900D03*
X333349Y1363500D03*
X311900Y1344900D03*
X286499Y1364050D03*
Y1345050D03*
X301699Y1395750D03*
X268499Y1453550D03*
X278000Y1422000D03*
X270599Y1408550D03*
X303499Y1411250D03*
X300899Y1433350D03*
X286600Y1449700D03*
X304699Y1457550D03*
X344099Y1449550D03*
Y1421150D03*
Y1393750D03*
X313600Y1442700D03*
X312800Y1467400D03*
X333349Y1429500D03*
X312100Y1420700D03*
X285499Y1418550D03*
Y1427550D03*
Y1399550D03*
X333349Y1393100D03*
Y1481900D03*
X332500Y1519700D03*
X296599Y1497150D03*
X312000Y1514600D03*
X286700Y1516100D03*
X267349Y1518150D03*
Y1522550D03*
X266999Y1512550D03*
X267349Y1527172D03*
X279499Y1510550D03*
Y1515050D03*
X279075Y1525957D03*
X278567Y1529925D03*
X305998Y1569114D03*
X293998Y1578114D03*
Y1573614D03*
Y1569114D03*
X289998Y1578114D03*
Y1573614D03*
Y1569114D03*
X307000Y1619600D03*
X344500Y1583600D03*
X337199Y1636350D03*
X278499Y1621550D03*
X265700Y1635100D03*
X289000Y1641800D03*
X320299Y1642950D03*
X316799Y1657450D03*
X302399Y1662950D03*
X284300Y1676900D03*
X334399Y1691650D03*
X329999Y1716950D03*
X291099Y1707450D03*
X335767Y1662735D03*
X318499Y1675550D03*
X299999Y1696050D03*
X270999Y1660550D03*
X273499Y1694050D03*
X280499Y1718550D03*
X320999Y1706050D03*
X303999Y1722050D03*
X343899Y1752650D03*
X297099Y1733850D03*
X270599Y1748950D03*
X290699Y1760750D03*
X286599Y1791850D03*
X327299D03*
X322299Y1802150D03*
X303999Y1800850D03*
X270599Y1801450D03*
X263499Y1734550D03*
X285499Y1742550D03*
X321999Y1733050D03*
X303499Y1753550D03*
X321499Y1772550D03*
X334999Y1797050D03*
X326301Y1766030D03*
X315499Y1812250D03*
X284299Y1811150D03*
X270299Y1867250D03*
X337499Y1855950D03*
X316999D03*
X298999D03*
X308099Y1880550D03*
X295299Y1870250D03*
X313599Y1889250D03*
Y1870250D03*
X326399Y1876250D03*
X336799Y1888950D03*
Y1869950D03*
X283999Y1856050D03*
X306999Y1932550D03*
X302499D03*
X298499D03*
X293999Y1933050D03*
X306000Y1961500D03*
X305500Y1965500D03*
X293999Y1971050D03*
Y1966550D03*
Y1962050D03*
X289499Y1961550D03*
Y1966550D03*
Y1971050D03*
X314099Y1901250D03*
X326899Y1907250D03*
X326399Y1895250D03*
X335799Y1916450D03*
X336799Y1897950D03*
X305999Y1913050D03*
X302499Y1922050D03*
X296858Y1956228D03*
X281999Y1918550D03*
Y1923550D03*
Y1928550D03*
X266999Y1915550D03*
Y1920050D03*
Y1924550D03*
Y1929050D03*
Y1933550D03*
X326799Y1977050D03*
X329999Y1987550D03*
X311500Y1987500D03*
X291499Y1987550D03*
X272000Y1987500D03*
X381499Y65550D03*
X376999D03*
X371999Y15550D03*
X376499D03*
X380999D03*
X369999Y23550D03*
Y19050D03*
X382499Y20050D03*
X416999Y25050D03*
X417499Y46550D03*
X416999Y63550D03*
X345499Y5050D03*
X364999Y4550D03*
X382499Y5050D03*
X395999Y5550D03*
X413499Y6050D03*
X381499Y70050D03*
X376999D03*
X381299Y136750D03*
X389599Y90950D03*
X400499Y134050D03*
Y119550D03*
X363999Y136050D03*
X417499Y79050D03*
Y93550D03*
Y108050D03*
Y125550D03*
X416999Y145050D03*
X360999Y113050D03*
X356499D03*
X351999D03*
X347499D03*
X360999Y100550D03*
X355999D03*
X350999D03*
X345999D03*
X387599Y220150D03*
X385999Y207250D03*
X354099Y175350D03*
X389299Y161650D03*
X400499Y151550D03*
X363999Y153550D03*
X369999Y219050D03*
X382499Y190550D03*
X355499Y219050D03*
X362999Y190050D03*
X416999Y164050D03*
X417999Y185050D03*
X423799Y259750D03*
X383299Y310250D03*
X386899Y299250D03*
X359399Y307250D03*
X347399Y301950D03*
X355999Y242750D03*
X347699Y269050D03*
X382999Y276650D03*
X412999Y307550D03*
Y290050D03*
Y275550D03*
X369499Y282550D03*
X381999Y254050D03*
X354999Y282550D03*
X362499Y253550D03*
X354099Y373050D03*
X368299Y386350D03*
X357999Y359050D03*
X380599Y381050D03*
X386599Y348450D03*
X394899Y357750D03*
X422499Y348150D03*
X422199Y363350D03*
X420199Y391350D03*
X419599Y458550D03*
X426599Y415350D03*
X415099Y422550D03*
X410799Y431150D03*
X354699Y426650D03*
X356399Y451750D03*
X351399Y470750D03*
X358399Y498650D03*
X357399Y521250D03*
Y530550D03*
Y543850D03*
X357999Y559450D03*
X415999Y518550D03*
X420199Y638550D03*
X427499Y624550D03*
X359399Y576050D03*
Y599650D03*
X360399Y615550D03*
X359699Y627550D03*
X345399Y698950D03*
X358899Y657150D03*
X359399Y669450D03*
X359199Y690650D03*
X357699Y707750D03*
X353999Y787750D03*
X347699Y773450D03*
X355999Y752850D03*
X424999Y766550D03*
X422999Y785050D03*
Y799550D03*
X418799Y896050D03*
Y877050D03*
X422499Y855550D03*
Y836550D03*
X422999Y817050D03*
X374500Y973500D03*
X375000Y939000D03*
Y1034000D03*
X424299Y1034050D03*
X423299Y1013050D03*
Y994050D03*
X373500Y1089500D03*
X419999Y1115550D03*
X409499Y1102550D03*
X416099Y1183550D03*
X415499Y1176050D03*
Y1161550D03*
X419499Y1219550D03*
X377499Y1210050D03*
Y1201050D03*
Y1182050D03*
X420099Y1241550D03*
X419499Y1234050D03*
X376599Y1293950D03*
X376499Y1264550D03*
Y1255550D03*
Y1236550D03*
X424999Y1278550D03*
X425499Y1290550D03*
X424999Y1259550D03*
X416699Y1342650D03*
X416199Y1367550D03*
X375599Y1323350D03*
X374499Y1375550D03*
Y1366550D03*
Y1347550D03*
X423299Y1430350D03*
X426799Y1416050D03*
X422299Y1394950D03*
X425799Y1447950D03*
X427099Y1469150D03*
X376299Y1437650D03*
X373099Y1456550D03*
X373499Y1430050D03*
Y1421050D03*
Y1402050D03*
X414799Y1532350D03*
X424299Y1541350D03*
X374099Y1554550D03*
X374799Y1491250D03*
X415999Y1603250D03*
X416199Y1625250D03*
X425499Y1635050D03*
X418299Y1561250D03*
X351899Y1570850D03*
X350600Y1610900D03*
X349099Y1634550D03*
X376099Y1572850D03*
X375099Y1608250D03*
X377700Y1629000D03*
X414799Y1653750D03*
X414399Y1678350D03*
X414499Y1707250D03*
X374999Y1656750D03*
X377099Y1696350D03*
X380099Y1709650D03*
X351099Y1691150D03*
X352000Y1700400D03*
X427499Y1662050D03*
X417799Y1790850D03*
X387899Y1802850D03*
X359499Y1736850D03*
X376799Y1734050D03*
X393499Y1759550D03*
X376499Y1775550D03*
X357999Y1796050D03*
X410757Y1772872D03*
X393999Y1784550D03*
X422999Y1778550D03*
X414499Y1810450D03*
X355699Y1810750D03*
X426499Y1855450D03*
X406999Y1855950D03*
X391499D03*
X369499D03*
X351999Y1855450D03*
X359999Y1878550D03*
X421399Y1888050D03*
X369799Y1880050D03*
X389499Y1885050D03*
X348999Y1879050D03*
X406499Y1874050D03*
X367299Y1956950D03*
X358999Y1925050D03*
X359999Y1897550D03*
Y1906550D03*
X420399Y1962550D03*
Y1934550D03*
Y1953550D03*
X421399Y1916050D03*
Y1907050D03*
X347699Y1972250D03*
X367999Y1940250D03*
X369199Y1919750D03*
X369999Y1901950D03*
X388499Y1959550D03*
Y1950550D03*
Y1932950D03*
X389499Y1913050D03*
Y1904050D03*
X349499Y1910050D03*
X348499Y1956550D03*
X347999Y1944550D03*
Y1925550D03*
X348999Y1898050D03*
X406999Y1905050D03*
X405999Y1951550D03*
X405499Y1939550D03*
Y1920550D03*
X406499Y1893050D03*
X385099Y1975950D03*
X420799Y1977250D03*
X399299Y1976750D03*
X367299Y1972950D03*
X420500Y1987000D03*
X403500D03*
X364999Y1987050D03*
X382499Y1987550D03*
X345499D03*
X436499Y50350D03*
Y31350D03*
X466799Y64750D03*
X465799Y43750D03*
Y24750D03*
X499999Y64050D03*
X500499Y47050D03*
X499999Y25550D03*
X432999Y6050D03*
X448499D03*
X467999Y5550D03*
X485499Y6050D03*
X498999D03*
X437499Y71350D03*
X442799Y142450D03*
X441799Y121450D03*
Y102450D03*
X471399Y124550D03*
X470399Y103550D03*
Y84550D03*
X473099Y141050D03*
X499999Y145550D03*
X500499Y126050D03*
Y108550D03*
Y79550D03*
Y94050D03*
X502899Y217150D03*
X504199Y193250D03*
X472999Y214550D03*
X483599Y179350D03*
X446799Y205650D03*
X445799Y184650D03*
Y165650D03*
X474099Y181050D03*
X473099Y160050D03*
X449999Y217050D03*
X430499D03*
X499999Y164550D03*
X466399Y304950D03*
X479299Y297250D03*
X437499Y307050D03*
Y289550D03*
Y275050D03*
X444499Y283050D03*
X463999Y283550D03*
X481499D03*
X495999D03*
X448999Y255550D03*
X469999Y254550D03*
X508499Y255050D03*
X488999Y254550D03*
X438999Y381550D03*
X458499Y382050D03*
X484900Y394700D03*
X485000Y373200D03*
X509999Y382550D03*
X443499Y354050D03*
X464499Y353050D03*
X502999Y353550D03*
X483499Y353050D03*
X498399Y470050D03*
X503699Y419250D03*
X472499Y458050D03*
X468799Y414250D03*
X443199Y440850D03*
X440099Y459250D03*
X431099Y479350D03*
X450300Y404200D03*
X490499Y464050D03*
X490999Y444550D03*
Y427050D03*
Y412550D03*
X454499Y472550D03*
X454999Y438550D03*
X454499Y458050D03*
X453999Y417550D03*
X430099Y551450D03*
X485299Y534550D03*
X508699Y498950D03*
X471499Y493950D03*
X452499Y565050D03*
X456499Y518050D03*
X435499Y519050D03*
X491499Y504050D03*
X490499Y483050D03*
X453999Y509550D03*
X454499Y490050D03*
X504499Y598050D03*
Y580550D03*
Y566050D03*
X479999Y598550D03*
Y581050D03*
Y566550D03*
X509999Y640550D03*
X452499Y597050D03*
Y579550D03*
X427999Y597550D03*
Y580050D03*
Y565550D03*
X506599Y711650D03*
X487299Y716950D03*
X451099Y711650D03*
X450399Y672750D03*
X444799Y687350D03*
X509999Y672550D03*
Y655050D03*
X488499Y691050D03*
Y673550D03*
Y659050D03*
X463999Y691550D03*
Y674050D03*
Y659550D03*
X467699Y772750D03*
X468699Y788350D03*
X472999Y736550D03*
X489599Y752450D03*
X490299Y734550D03*
X453399Y807950D03*
X452099Y781450D03*
Y762450D03*
X435299Y795150D03*
Y777650D03*
Y763150D03*
X437299Y744650D03*
X495999Y795050D03*
X475699Y880450D03*
X479599Y847550D03*
X462999Y884050D03*
Y865050D03*
X453399Y826950D03*
X434799Y833650D03*
Y814650D03*
X464499Y896050D03*
X493499Y884050D03*
Y865050D03*
X493999Y845550D03*
Y813550D03*
Y828050D03*
X506899Y919950D03*
Y900950D03*
X443599Y945650D03*
X442599Y924650D03*
Y905650D03*
X486799Y941050D03*
X485799Y920050D03*
Y901050D03*
X461999Y966050D03*
X462499Y946550D03*
Y914550D03*
Y929050D03*
X494099Y1017350D03*
X493099Y996350D03*
X462499Y1043850D03*
X461999Y985050D03*
X474499Y1115050D03*
X491999Y1115550D03*
X454999D03*
X439499D03*
X501499Y1102550D03*
X463999Y1102050D03*
X481499Y1102550D03*
X444499D03*
X428999D03*
X436999Y1142550D03*
Y1128050D03*
X504399Y1132250D03*
X473099Y1144550D03*
X453499Y1140550D03*
X484499Y1085850D03*
X483499Y1064850D03*
X433599Y1085550D03*
X432599Y1064550D03*
X463499Y1083850D03*
X462499Y1062850D03*
X437599Y1150050D03*
X487099Y1218050D03*
X486499Y1210550D03*
Y1196050D03*
X443199Y1224250D03*
X507199Y1224350D03*
X506599Y1202350D03*
Y1216850D03*
X505399Y1153250D03*
X474099Y1165550D03*
X454499Y1161550D03*
X443799Y1274250D03*
Y1246250D03*
Y1265250D03*
X443199Y1238750D03*
X507199Y1252350D03*
Y1243350D03*
X465499Y1284550D03*
Y1293550D03*
Y1265550D03*
X498299Y1323350D03*
X468999Y1323950D03*
X428499Y1325350D03*
X508599Y1370550D03*
X444899Y1377950D03*
X434499Y1360250D03*
X448099Y1341250D03*
X473999Y1342450D03*
X485599Y1367550D03*
X468699Y1362850D03*
X466699Y1378150D03*
X498899Y1386450D03*
X499199Y1350550D03*
X459699Y1468050D03*
X464199Y1401450D03*
X459999Y1424050D03*
X498899Y1408350D03*
X500899Y1434350D03*
X505899Y1466250D03*
X482599Y1449950D03*
X456399Y1445950D03*
X445099Y1464250D03*
X478299Y1464850D03*
X481499Y1417050D03*
Y1402550D03*
X441499Y1431550D03*
Y1414050D03*
Y1399550D03*
X499699Y1538950D03*
X466999Y1530650D03*
X488299Y1531050D03*
X461399Y1541650D03*
X474299Y1544750D03*
X452199Y1550650D03*
X444299Y1532650D03*
X439599Y1552150D03*
X465999Y1603450D03*
X487099Y1606250D03*
X449199Y1579050D03*
X443799Y1612250D03*
X460199Y1632850D03*
X484999Y1636550D03*
X501399Y1634550D03*
X508199Y1610450D03*
X510100Y1579800D03*
X472299Y1572050D03*
X502199Y1566250D03*
X472499Y1620550D03*
Y1611550D03*
X484200Y1579900D03*
X432499Y1617550D03*
X434500Y1579500D03*
X431999Y1605550D03*
X435300Y1715300D03*
X448399Y1699450D03*
X447699Y1682850D03*
X449599Y1656950D03*
X483599Y1662550D03*
X485599Y1694850D03*
X502899Y1709650D03*
X507399Y1683350D03*
X509199Y1660550D03*
X468499Y1712550D03*
X467999Y1687050D03*
Y1696050D03*
Y1668050D03*
X432400Y1680100D03*
X428600Y1691200D03*
X436799Y1772550D03*
X472699Y1792150D03*
X429499Y1748050D03*
X458499Y1742050D03*
X441499Y1758050D03*
X480999Y1756050D03*
X463999Y1772050D03*
X445499Y1792550D03*
X508200Y1758200D03*
X484999Y1779050D03*
X496999Y1799550D03*
X481299Y1811150D03*
X448099Y1809450D03*
X499999Y1854950D03*
X480499Y1855450D03*
X464999D03*
X443999Y1855950D03*
X476199Y1877450D03*
X434299Y1876050D03*
X446999Y1880050D03*
X492999Y1878050D03*
X504799Y1967550D03*
Y1939550D03*
Y1958550D03*
X505799Y1921050D03*
Y1912050D03*
Y1893050D03*
X475199Y1951950D03*
Y1923950D03*
Y1942950D03*
X476199Y1905450D03*
Y1896450D03*
X459299Y1966850D03*
Y1938850D03*
Y1957850D03*
X460299Y1920350D03*
Y1911350D03*
Y1892350D03*
X433299Y1950550D03*
Y1922550D03*
Y1941550D03*
X434299Y1904050D03*
Y1895050D03*
X445999Y1954550D03*
Y1945550D03*
Y1926550D03*
X446999Y1908050D03*
Y1899050D03*
X493499Y1909050D03*
X492499Y1955550D03*
X491999Y1943550D03*
Y1924550D03*
X492999Y1897050D03*
X509299Y1977250D03*
X493799D03*
X473299D03*
X455799Y1976750D03*
X436299Y1977250D03*
X492500Y1987500D03*
X476000Y1987000D03*
X456500Y1987500D03*
X438999Y1987550D03*
X522899Y64350D03*
Y45350D03*
X587999Y63550D03*
X588499Y46550D03*
X587999Y25050D03*
X541499Y63550D03*
X541999Y46550D03*
X541499Y25050D03*
X516499Y6550D03*
X535999D03*
X551499D03*
X570999Y6050D03*
X588499Y6550D03*
X523899Y85350D03*
X520299Y141450D03*
Y122450D03*
X569099Y112550D03*
X568099Y91550D03*
Y72550D03*
X562799Y146750D03*
Y127750D03*
X587999Y145050D03*
X588499Y125550D03*
X541499Y145050D03*
X541999Y125550D03*
Y108050D03*
Y79050D03*
Y93550D03*
X565999Y199950D03*
X528799D03*
X521299Y162450D03*
X563799Y167750D03*
X587999Y217050D03*
X568499Y217550D03*
X552999D03*
X533499D03*
X588999Y185050D03*
X587999Y164050D03*
X542499Y185050D03*
X541499Y164050D03*
X544799Y293950D03*
X540099Y306550D03*
X516899Y306950D03*
X515499Y284050D03*
X536499Y283050D03*
X525999Y255050D03*
X540499D03*
X572999Y287050D03*
X572499Y306550D03*
X572999Y269550D03*
Y255050D03*
X558099Y335050D03*
X557933Y331010D03*
X557999Y322550D03*
Y326550D03*
X579899Y375750D03*
X530999Y381550D03*
X520499Y353550D03*
X548100Y362200D03*
X573499Y346550D03*
X572499Y325550D03*
X577899Y460550D03*
X578399Y441050D03*
X577399Y420050D03*
X539799Y466050D03*
X538799Y445050D03*
X576099Y481850D03*
X511299Y449150D03*
X519499Y471550D03*
X518999Y416550D03*
X592499Y478050D03*
Y459050D03*
X592999Y439550D03*
Y422050D03*
Y407550D03*
X556499Y467550D03*
X555999Y412550D03*
X539299Y485550D03*
X576599Y522350D03*
X577099Y502850D03*
X579499Y561550D03*
X558499Y562550D03*
X538999Y562050D03*
X535499Y545050D03*
X514499Y546050D03*
X518999Y508550D03*
X519499Y489050D03*
X555999Y504550D03*
X556499Y485050D03*
X558499Y616050D03*
X554304Y615840D03*
X554499Y624550D03*
X558699D03*
X554499Y620050D03*
X558709Y620245D03*
X534499Y640050D03*
X586299Y711250D03*
X565699Y710650D03*
X549999Y710050D03*
X547999Y728550D03*
X573499Y690550D03*
Y673050D03*
Y658550D03*
X534499Y672050D03*
Y654550D03*
Y805950D03*
X511199Y782050D03*
X527499Y747150D03*
X525499Y772450D03*
X547499Y799050D03*
Y780050D03*
X547999Y760550D03*
Y743050D03*
X575499Y802050D03*
X575999Y782550D03*
Y765050D03*
X577999Y732050D03*
X575999Y750550D03*
X526499Y851150D03*
X510899Y868150D03*
X578299Y895650D03*
X541399Y873450D03*
Y854450D03*
X512899Y842550D03*
Y823550D03*
X521999Y895550D03*
X522499Y876050D03*
X576499Y842050D03*
X575499Y821050D03*
X583299Y961450D03*
X578299Y914650D03*
X540299Y956850D03*
X539299Y935850D03*
X570899Y965850D03*
Y946850D03*
X521999Y914550D03*
X562999Y898050D03*
X560499Y968050D03*
X560999Y948550D03*
Y916550D03*
Y931050D03*
X516499Y957050D03*
X514499Y975550D03*
X583299Y980450D03*
X534599Y1048550D03*
X571899Y986850D03*
X573499Y1055550D03*
Y1036550D03*
X541899Y1021450D03*
X540899Y1000450D03*
Y981450D03*
X560499Y987050D03*
X560999Y999050D03*
X558999Y1049550D03*
Y1017550D03*
Y1032050D03*
X513999Y1046050D03*
Y1027050D03*
X514499Y1007550D03*
Y990050D03*
X588499Y1101550D03*
X578999Y1114550D03*
X568499Y1101550D03*
X564499Y1116050D03*
X548999D03*
X529499D03*
X511999Y1115550D03*
X553999Y1103050D03*
X538499D03*
X518999D03*
X535599Y1069550D03*
X574499Y1076550D03*
X558499Y1088050D03*
Y1069050D03*
X547099Y1202750D03*
Y1221750D03*
X546499Y1180750D03*
Y1195250D03*
X567999Y1215550D03*
Y1206550D03*
Y1187550D03*
X527999Y1212550D03*
X527499Y1200550D03*
Y1181550D03*
X579299Y1300750D03*
X527499Y1278150D03*
X530499Y1297050D03*
X561099Y1301050D03*
X566399Y1273850D03*
X549399Y1302850D03*
Y1274850D03*
Y1293850D03*
X548799Y1252850D03*
Y1267350D03*
X547099Y1230750D03*
X583299Y1283250D03*
Y1255250D03*
Y1274250D03*
X582699Y1233250D03*
Y1247750D03*
X565999Y1248550D03*
Y1234050D03*
X525999Y1263050D03*
Y1245550D03*
Y1231050D03*
X555699Y1322950D03*
X581999Y1370150D03*
X559099Y1343250D03*
X545099Y1355250D03*
X518499Y1346950D03*
X540399Y1382150D03*
X523999Y1391050D03*
X523499Y1360050D03*
Y1379050D03*
X580999Y1412750D03*
X575699Y1438950D03*
X538799Y1409750D03*
X536799Y1436350D03*
X528499Y1460250D03*
X546099Y1467550D03*
X582999Y1461250D03*
X557499Y1443050D03*
Y1452050D03*
Y1424050D03*
X516999Y1437050D03*
X517499Y1449050D03*
X516999Y1418050D03*
X563499Y1497550D03*
Y1486550D03*
Y1503550D03*
Y1492050D03*
X590599Y1483450D03*
X529799Y1555050D03*
X567999Y1549950D03*
X582299Y1534150D03*
X538999Y1528350D03*
X518899Y1530150D03*
X532499Y1635550D03*
X552099Y1601950D03*
X553399Y1624550D03*
X590799Y1627850D03*
X588000Y1604000D03*
X588099Y1572050D03*
X552199Y1576650D03*
X569499Y1619550D03*
Y1610550D03*
X573400Y1577600D03*
X529499Y1616550D03*
X533800Y1575500D03*
X528999Y1604550D03*
X518499Y1643950D03*
X538299Y1721050D03*
X532599Y1655650D03*
X554199Y1651950D03*
X555199Y1674750D03*
X555399Y1689350D03*
X555899Y1706750D03*
X580299Y1722550D03*
X590599Y1694450D03*
X580799Y1646150D03*
X572999Y1694550D03*
Y1703550D03*
Y1675550D03*
X532499Y1688550D03*
X532999Y1700550D03*
X532499Y1669550D03*
X582599Y1740050D03*
X560399Y1792550D03*
X555500Y1802700D03*
X539499Y1788150D03*
X526499Y1801150D03*
X556199Y1727050D03*
X522300Y1739200D03*
X532499Y1763050D03*
X515499Y1779050D03*
X544300Y1784638D03*
X531799Y1818450D03*
X514199Y1815750D03*
X591499Y1855950D03*
X573999Y1855450D03*
X554499Y1855950D03*
X538999D03*
X517499Y1855450D03*
X588899Y1882350D03*
X562599Y1874450D03*
X519399Y1876750D03*
X533499Y1884050D03*
X575999Y1888050D03*
X587899Y1956850D03*
Y1928850D03*
Y1947850D03*
X588899Y1910350D03*
Y1901350D03*
X561599Y1948950D03*
Y1920950D03*
Y1939950D03*
X562599Y1902450D03*
Y1893450D03*
X546999Y1966850D03*
Y1938850D03*
Y1957850D03*
X547999Y1920350D03*
Y1911350D03*
Y1892350D03*
X518399Y1951250D03*
Y1923250D03*
Y1942250D03*
X519399Y1904750D03*
Y1895750D03*
X532499Y1958550D03*
Y1949550D03*
Y1930550D03*
X533499Y1912050D03*
Y1903050D03*
X575999Y1907050D03*
X576499Y1919050D03*
X574999Y1953550D03*
X575499Y1965550D03*
X574999Y1934550D03*
X585799Y1976250D03*
X570299D03*
X546299Y1977250D03*
X528799Y1976750D03*
X568999Y1987050D03*
X553499D03*
X588499Y1986550D03*
X511999Y1987550D03*
X531500Y1987500D03*
X603999Y54350D03*
Y35350D03*
X651799Y59650D03*
Y40650D03*
X674999Y59050D03*
X675499Y42050D03*
X674999Y20550D03*
X624499Y61550D03*
X624999Y44550D03*
X624499Y23050D03*
X608499Y6550D03*
X625999Y7050D03*
X645499D03*
X660999D03*
X604999Y75350D03*
X603999Y133750D03*
X652799Y80650D03*
X649899Y138350D03*
X674999Y140550D03*
X675499Y121050D03*
Y103550D03*
Y74550D03*
Y89050D03*
X624499Y143050D03*
X624999Y123550D03*
X623899Y202550D03*
X604999Y173750D03*
X603999Y152750D03*
X650899Y178350D03*
X649899Y157350D03*
X662499Y218050D03*
X642999D03*
X625499Y217550D03*
X605499D03*
X675999Y180550D03*
X674999Y159550D03*
X625499Y183050D03*
X624499Y162050D03*
X656499Y307050D03*
X653999Y286550D03*
X627999Y280050D03*
X627499Y299550D03*
X627999Y262550D03*
Y248050D03*
X599799Y385150D03*
X600299Y365650D03*
X599299Y344650D03*
X659899Y363250D03*
X632399Y358750D03*
X635399Y376250D03*
X607399Y380250D03*
X643599Y395950D03*
X655999Y344050D03*
X656499Y324550D03*
X628499Y339550D03*
X628200Y320000D03*
X644099Y450950D03*
X644599Y416950D03*
X644099Y436450D03*
X621499Y466550D03*
X621999Y432550D03*
X621499Y452050D03*
X620999Y411550D03*
X666999Y476550D03*
X643499Y546750D03*
X642499Y525750D03*
X613700Y504600D03*
X621499Y484050D03*
X593499Y499050D03*
X666499Y547050D03*
X666999Y508550D03*
X666499Y528050D03*
X666999Y491050D03*
X642999Y566250D03*
X640599Y604650D03*
X673999Y645150D03*
X645099Y639150D03*
X631999Y639650D03*
X665999Y623550D03*
X620499D03*
Y609050D03*
X595999Y641550D03*
Y624050D03*
Y609550D03*
X674999Y601550D03*
X646999Y584550D03*
X625999Y585050D03*
X606499Y584550D03*
X667499Y568050D03*
X651999Y718350D03*
X648999Y702350D03*
X629099Y714050D03*
X605299Y661750D03*
X609499Y708050D03*
X607499Y726550D03*
X647499Y689050D03*
Y671550D03*
Y657050D03*
X622999Y689550D03*
Y672050D03*
X597999Y690050D03*
X647399Y742150D03*
X653099Y803350D03*
X621499Y767150D03*
X633499Y750150D03*
X606999Y797050D03*
Y778050D03*
X607499Y758550D03*
Y741050D03*
X664999Y805050D03*
Y786050D03*
X665499Y766550D03*
X645799Y816650D03*
X642599Y883250D03*
X641599Y862250D03*
Y843250D03*
X621999Y835050D03*
X612999Y854550D03*
X629499Y853050D03*
Y868550D03*
X613499Y868050D03*
X663499Y896050D03*
X663999Y876550D03*
Y844550D03*
Y859050D03*
X665999Y826050D03*
X639499Y971150D03*
Y952150D03*
X616699Y967250D03*
Y948250D03*
X658999Y959050D03*
X656999Y977550D03*
X603499Y904050D03*
X601499Y954550D03*
Y922550D03*
Y937050D03*
X664499Y936050D03*
X663499Y915050D03*
X673999Y1036550D03*
Y1017550D03*
X674699Y1061450D03*
X611399Y1045650D03*
Y1026650D03*
X617699Y988250D03*
X656499Y1048050D03*
Y1029050D03*
X656999Y1009550D03*
Y992050D03*
X631999Y1001550D03*
X629999Y1052050D03*
Y1020050D03*
Y1034550D03*
X600999Y1002050D03*
X598999Y1052550D03*
Y1020550D03*
Y1035050D03*
X633999Y1103050D03*
X669499Y1116550D03*
X616499Y1115050D03*
X605999Y1102050D03*
X598999Y1114550D03*
X674699Y1080450D03*
X674999Y1134950D03*
X641799Y1137650D03*
X627699Y1143550D03*
X612399Y1066650D03*
X629499Y1090550D03*
Y1071550D03*
X598499Y1091050D03*
Y1072050D03*
X603899Y1157850D03*
X626199Y1183450D03*
X597599Y1196050D03*
X596599Y1215050D03*
X651599Y1203050D03*
X650599Y1182050D03*
X651299Y1174150D03*
X650299Y1153150D03*
X668199Y1173850D03*
X667199Y1152850D03*
X671199Y1213750D03*
X670199Y1192750D03*
X628699Y1164550D03*
X668699Y1227650D03*
X672999Y1303450D03*
X608899Y1305050D03*
X600899Y1238650D03*
X630499Y1243950D03*
X657099Y1272850D03*
X657799Y1288450D03*
X656399Y1307050D03*
X618199Y1296250D03*
Y1268250D03*
Y1287250D03*
X617599Y1246250D03*
Y1260750D03*
X638999Y1286550D03*
Y1295550D03*
Y1267550D03*
X598499Y1280550D03*
X598999Y1292550D03*
X598499Y1261550D03*
X671999Y1324950D03*
X631799Y1322650D03*
X605599Y1326350D03*
X665699Y1337250D03*
X606199Y1338250D03*
X617899Y1360850D03*
X625499Y1383450D03*
X632499Y1347950D03*
X599999Y1382550D03*
X599499Y1351550D03*
Y1370550D03*
X654999Y1385050D03*
X654499Y1373050D03*
Y1354050D03*
X659699Y1445950D03*
X604899Y1407750D03*
X601299Y1447650D03*
X636799Y1461250D03*
X626799Y1432350D03*
X627499Y1406050D03*
X665699Y1462250D03*
X652999Y1435550D03*
Y1418050D03*
Y1403550D03*
X656099Y1479550D03*
X625199Y1489150D03*
X610899Y1496750D03*
X672399Y1508750D03*
X673699Y1535350D03*
X662099Y1549650D03*
X643099Y1541350D03*
X599799Y1544650D03*
X617699Y1530350D03*
X670699Y1603150D03*
X671399Y1625350D03*
X628499Y1636650D03*
X633499Y1615450D03*
X635500Y1603900D03*
X652399Y1575850D03*
X623499Y1564050D03*
X652499Y1618550D03*
Y1609550D03*
X639200Y1576200D03*
X612499Y1615550D03*
X611900Y1577900D03*
X611999Y1603550D03*
X649399Y1644950D03*
X657099Y1668850D03*
X635099Y1691150D03*
X607599Y1716450D03*
X593399Y1668850D03*
X627299Y1659550D03*
X600599Y1645450D03*
X674999Y1676550D03*
X656499Y1697050D03*
X609499Y1692050D03*
Y1675050D03*
X642499Y1709050D03*
X665399Y1752350D03*
X650399Y1771250D03*
X593299Y1760950D03*
X619499Y1803150D03*
X627273Y1793905D03*
X606999Y1745550D03*
X625499Y1725050D03*
X675499Y1757050D03*
X675999Y1769050D03*
X675499Y1738050D03*
X642400Y1800100D03*
X659159Y1792278D03*
X626999Y1800050D03*
X645099Y1877550D03*
X667999Y1870950D03*
X632799Y1820450D03*
X627494Y1829068D03*
X608599Y1810750D03*
X669399Y1855350D03*
X627499Y1855950D03*
X611999D03*
X630699Y1872750D03*
X602799Y1887350D03*
X640999Y1815550D03*
X595199Y1820910D03*
X659549Y1815384D03*
X644049Y1810834D03*
X633837Y1807384D03*
X646799Y1926450D03*
X645399Y1906150D03*
X673899Y1966850D03*
Y1938850D03*
Y1957850D03*
X674899Y1920350D03*
Y1911350D03*
Y1892350D03*
X660299Y1964550D03*
Y1936550D03*
Y1955550D03*
X661299Y1918050D03*
Y1909050D03*
Y1890050D03*
X629699Y1947250D03*
Y1919250D03*
Y1938250D03*
X630699Y1900750D03*
Y1891750D03*
X601799Y1961850D03*
Y1933850D03*
Y1952850D03*
X602799Y1915350D03*
Y1906350D03*
X616499Y1913050D03*
Y1922050D03*
Y1894050D03*
X615499Y1959550D03*
Y1968550D03*
Y1940550D03*
X644999Y1953050D03*
X645499Y1965050D03*
X644999Y1934050D03*
X659299Y1976250D03*
X643799D03*
X622799D03*
X605299Y1975750D03*
X642499Y1987050D03*
X626999D03*
X661999Y1986550D03*
X605999Y1987050D03*
X751499Y48350D03*
X694999Y62650D03*
X757499Y63050D03*
Y44050D03*
X725499Y62050D03*
X725999Y45050D03*
X725499Y23550D03*
X680499Y6550D03*
X697999Y7050D03*
X712499Y6050D03*
X729999Y6550D03*
X749499D03*
X752099Y112150D03*
X738199Y137450D03*
X695999Y102650D03*
X694999Y81650D03*
X699699Y141750D03*
X758499Y84050D03*
X725499Y143550D03*
X725999Y124050D03*
Y106550D03*
Y77550D03*
Y92050D03*
X757999Y154550D03*
Y159050D03*
X753999Y154550D03*
Y159050D03*
X728899Y204550D03*
X688999Y196550D03*
X700699Y181750D03*
X699699Y160750D03*
X749499Y218550D03*
X729499D03*
X711999Y218050D03*
X677999D03*
X726499Y183550D03*
X725499Y162550D03*
X755499Y314550D03*
X751539Y313984D03*
X711999Y307550D03*
Y293050D03*
X723200Y275500D03*
X711499Y252550D03*
X680500Y280700D03*
X682999Y300050D03*
X683499Y263050D03*
Y248550D03*
X755346Y319149D03*
X751499Y318050D03*
X748000Y357500D03*
X749899Y398550D03*
X711499Y344550D03*
X711999Y325050D03*
X683999Y340050D03*
X682999Y319050D03*
X713699Y455450D03*
X713199Y474950D03*
X712699Y434450D03*
X750399Y453550D03*
X750899Y419550D03*
X750399Y439050D03*
X694999Y480550D03*
X737999Y467050D03*
X691399Y548350D03*
X755699Y528650D03*
X756199Y509150D03*
X755199Y488150D03*
X754499Y564650D03*
X713099Y561550D03*
X713599Y542050D03*
X712599Y521050D03*
X713199Y489450D03*
X695499Y521050D03*
X695999Y501550D03*
X737999Y559050D03*
X738499Y539550D03*
Y522050D03*
Y507550D03*
X738999Y488050D03*
X691899Y588850D03*
X692399Y569350D03*
X754999Y605150D03*
X755499Y585650D03*
X717099Y636050D03*
X729699Y640350D03*
X731499Y604050D03*
Y586550D03*
Y572050D03*
X690499Y623050D03*
X744999Y626550D03*
X721499Y617550D03*
X699999Y610050D03*
X751499Y679148D03*
X749499Y716050D03*
X744999Y715550D03*
X749999Y720050D03*
X745499D03*
X757400Y686300D03*
X720899Y712250D03*
X732499Y729250D03*
X681899Y713650D03*
X679299Y703050D03*
X727099Y715050D03*
X739399Y688150D03*
X747999Y670750D03*
X723499Y654850D03*
X693999Y648150D03*
X754999Y694050D03*
X702999Y688050D03*
Y670550D03*
Y656050D03*
X678499Y688550D03*
Y671050D03*
X749999Y700050D03*
X750000Y755500D03*
X710899Y751150D03*
X696299Y741850D03*
X685999Y780050D03*
X694599Y763450D03*
X743099Y785350D03*
X733799Y761450D03*
X716599Y736850D03*
X723999Y802350D03*
Y783350D03*
X687099Y804650D03*
X706999Y811550D03*
Y792550D03*
X707499Y773050D03*
X728499Y841850D03*
X724999Y823350D03*
X688099Y844650D03*
X687099Y823650D03*
X729999Y881850D03*
Y862850D03*
X751599Y887350D03*
X705999Y851050D03*
Y865550D03*
X707999Y832550D03*
X751499Y855550D03*
Y836550D03*
X751999Y817050D03*
X707399Y918550D03*
Y899550D03*
X678299Y978350D03*
X730999Y902850D03*
X688099Y936350D03*
X687099Y915350D03*
Y896350D03*
X724699Y976250D03*
X723699Y955250D03*
Y936250D03*
X752599Y927350D03*
X751599Y906350D03*
X706499Y942550D03*
X749999Y965550D03*
Y946550D03*
X751399Y1023550D03*
Y1004550D03*
X752399Y1052550D03*
X734999Y1030550D03*
Y1045050D03*
X713999Y1049050D03*
Y1031550D03*
Y1017050D03*
X678299Y997350D03*
X694999Y993050D03*
X692999Y1043550D03*
Y1011550D03*
Y1026050D03*
X750999Y986550D03*
X755499Y1119050D03*
X749999Y1119550D03*
X748999Y1115550D03*
X748499Y1111550D03*
X734999Y1062550D03*
X713499Y1068550D03*
X737999Y1119050D03*
X727499Y1106050D03*
X720499Y1118550D03*
X709999Y1105550D03*
X700499Y1118550D03*
X689999Y1105550D03*
X727499Y1132650D03*
X704299D03*
X692499Y1082050D03*
Y1063050D03*
X753999Y1100050D03*
X747000Y1159000D03*
X713599Y1214650D03*
X756799Y1217650D03*
X758799Y1190150D03*
Y1199150D03*
X717999Y1169150D03*
X716999Y1148150D03*
X714399Y1199750D03*
X713399Y1178750D03*
X735999Y1220550D03*
Y1206050D03*
X737999Y1187550D03*
Y1178550D03*
Y1159550D03*
X695999Y1217550D03*
Y1203050D03*
X697999Y1184550D03*
X697499Y1172550D03*
Y1153550D03*
X684299Y1249550D03*
X740799Y1298750D03*
X723499Y1292650D03*
Y1278150D03*
X725499Y1250650D03*
Y1259650D03*
Y1231650D03*
X755399Y1300650D03*
Y1286150D03*
X757399Y1258650D03*
Y1267650D03*
Y1239650D03*
X756799Y1232150D03*
X709699Y1264550D03*
X708699Y1243550D03*
X740499Y1252550D03*
Y1270050D03*
X695999Y1235050D03*
X739199Y1348950D03*
X742099Y1320650D03*
X719199Y1322350D03*
X695999Y1323350D03*
X677999Y1347550D03*
X680299Y1365850D03*
X713899Y1386450D03*
X707899Y1346250D03*
X734199Y1373850D03*
X694999Y1388050D03*
Y1379050D03*
Y1360050D03*
X702299Y1404450D03*
X736199Y1399050D03*
X741099Y1450250D03*
X737799Y1428350D03*
X716899Y1459850D03*
X700899Y1450250D03*
X681299Y1393150D03*
X678299Y1425050D03*
X686999Y1468850D03*
X719499Y1446650D03*
X721899Y1419050D03*
X754999Y1420050D03*
Y1437550D03*
X692999Y1421050D03*
Y1406550D03*
X751000Y1517000D03*
X757500Y1522500D03*
X751000Y1521000D03*
Y1525000D03*
X741099Y1498150D03*
X729199Y1492750D03*
X716199Y1503050D03*
X735799Y1533650D03*
X714599Y1533950D03*
X708899Y1549250D03*
X685299Y1551950D03*
X747199Y1509150D03*
X755499Y1507550D03*
X734499Y1563550D03*
X722199Y1564250D03*
X706700Y1579900D03*
X698599Y1568550D03*
X681299Y1579150D03*
X693599Y1602450D03*
X686699Y1638650D03*
X742000Y1560000D03*
X743400Y1578700D03*
X719999Y1605050D03*
X751300Y1604900D03*
X732999Y1620050D03*
X756299Y1679050D03*
X738799Y1677250D03*
X750099Y1694950D03*
X756499Y1712150D03*
X739199Y1716750D03*
X721199Y1723750D03*
X727399Y1694350D03*
X717099Y1702450D03*
X693099Y1722350D03*
X691999Y1660550D03*
X751999Y1775550D03*
X756617Y1780067D03*
X752657Y1779496D03*
X755999Y1775550D03*
X756900Y1766000D03*
X753558Y1769946D03*
X757518Y1770517D03*
X752900Y1766000D03*
X751899Y1752150D03*
X747799Y1766750D03*
X729499Y1778750D03*
X729999Y1756450D03*
X747499Y1734350D03*
X702599Y1730550D03*
X709099Y1751850D03*
X690499Y1744950D03*
X694599Y1768450D03*
X715999Y1763050D03*
Y1772050D03*
Y1744050D03*
X693549Y1793134D03*
X706549Y1793634D03*
X744049Y1791634D03*
X740549Y1802634D03*
X753949Y1798194D03*
X717000Y1812384D03*
X705000Y1811900D03*
X686999Y1870250D03*
X728099Y1844750D03*
X747599Y1844250D03*
X743799Y1888850D03*
X728299D03*
X753699Y1879250D03*
X732199Y1878750D03*
X744699Y1868450D03*
X758399Y1868350D03*
X723199Y1867950D03*
X743399Y1855850D03*
X725899Y1855350D03*
X690899Y1855850D03*
X706399D03*
X697999Y1844550D03*
X732999Y1868550D03*
X711500Y1817700D03*
X704300Y1828400D03*
X686473Y1818375D03*
X740549Y1810384D03*
X750000Y1965500D03*
X696299Y1898850D03*
X716599Y1918450D03*
X728799Y1933050D03*
X709199Y1962950D03*
X698299Y1948050D03*
X676399Y1901150D03*
X695299Y1926450D03*
X711899Y1944050D03*
X736799Y1919450D03*
X728799Y1908150D03*
X705599Y1891850D03*
X730499Y1954650D03*
X755299Y1902150D03*
X739799D03*
X685499Y1959050D03*
Y1968050D03*
Y1940050D03*
X755500Y1914500D03*
X721499Y1974550D03*
X696299Y1976250D03*
X678799Y1975750D03*
X754999Y1987550D03*
X737499Y1987050D03*
X717999Y1987550D03*
X702499D03*
X679499Y1987050D03*
X774399Y54050D03*
X763399Y24150D03*
X817599Y43750D03*
X824899Y25150D03*
X813299Y68350D03*
Y49350D03*
X796999Y65550D03*
X797499Y48550D03*
X796999Y27050D03*
X764999Y6550D03*
X784499Y6050D03*
X801999Y6550D03*
X818999Y6050D03*
X836499Y6550D03*
X840499Y55050D03*
X839999Y46050D03*
X840999Y62550D03*
X778399Y105250D03*
X775399Y80250D03*
X821199Y137450D03*
X813299Y110850D03*
X805899Y126150D03*
X767399Y140150D03*
X796599Y123450D03*
X814299Y89350D03*
X796999Y147050D03*
X797499Y127550D03*
Y110050D03*
Y81050D03*
Y95550D03*
X837499Y138550D03*
X838499Y145050D03*
X837999Y91050D03*
X838999Y85050D03*
X838499Y99550D03*
Y107050D03*
X839499Y119050D03*
X841499Y71550D03*
X760799Y181950D03*
X779399Y200550D03*
X786499Y219050D03*
X800999Y216550D03*
X766999Y219050D03*
X797999Y187050D03*
X796999Y166050D03*
X838999Y313550D03*
X821499Y314050D03*
X809373Y307571D03*
Y297571D03*
Y292571D03*
X808999Y303050D03*
X796873Y307571D03*
Y303071D03*
Y298571D03*
Y294071D03*
X784478Y355424D03*
Y359924D03*
X781478Y363924D03*
X776978D03*
X772478Y359924D03*
Y363924D03*
X839299Y390950D03*
X819299Y394250D03*
X838499Y352050D03*
X840299Y430950D03*
X839299Y409950D03*
X820299Y434250D03*
X819299Y413250D03*
X802999Y466050D03*
X774999Y476550D03*
Y462050D03*
X825399Y540950D03*
X825899Y521450D03*
X824899Y500450D03*
X835599Y564050D03*
X834599Y543050D03*
X802999Y558050D03*
X803499Y538550D03*
Y521050D03*
Y506550D03*
X803999Y487050D03*
X775499Y553550D03*
X774499Y532550D03*
X774999Y494050D03*
X774499Y513550D03*
X835099Y583550D03*
X814499Y601550D03*
Y584050D03*
Y569550D03*
X789999Y602050D03*
Y584550D03*
Y570050D03*
X785499Y641050D03*
X777499Y638050D03*
X771800Y686600D03*
X786500Y686100D03*
X798000Y686400D03*
X764599Y655750D03*
X777499Y664550D03*
X794999D03*
X806300Y670600D03*
X841000Y671100D03*
X766499Y699050D03*
X782999Y699550D03*
X836149Y714050D03*
X766499Y705550D03*
X806831Y701853D03*
Y706853D03*
Y711853D03*
X794331Y698353D03*
Y702853D03*
Y707353D03*
Y711853D03*
X806999Y697050D03*
X771196Y764382D03*
Y760382D03*
X775696Y764382D03*
X780196D03*
X783196Y760382D03*
Y755882D03*
X799385Y761436D03*
X778999Y806950D03*
X763099Y796350D03*
X835999Y799050D03*
Y781550D03*
Y767050D03*
X811499Y799550D03*
Y782050D03*
Y767550D03*
X837799Y754150D03*
X825199Y850850D03*
X827699Y892450D03*
Y873450D03*
X776199Y879250D03*
X775199Y858250D03*
Y839250D03*
X800999Y892550D03*
X802999Y874050D03*
X801999Y853050D03*
Y834050D03*
X802499Y814550D03*
X828699Y913450D03*
X826999Y963150D03*
X773199Y960650D03*
X772199Y939650D03*
Y920650D03*
X800499Y944050D03*
Y963050D03*
X800999Y924550D03*
Y907050D03*
Y1037550D03*
Y1005550D03*
Y1020050D03*
X827999Y1003150D03*
X826999Y982150D03*
X777899Y1028050D03*
X776899Y1007050D03*
Y988050D03*
X801499Y984050D03*
X783999Y1096550D03*
X760999Y1095550D03*
X789499Y1099550D03*
X773499Y1101050D03*
X769499D03*
X773499Y1105050D03*
X769499D03*
X836149Y1118550D03*
X811499Y1097050D03*
X807499D03*
X807341Y1116216D03*
Y1111216D03*
Y1101216D03*
X806999Y1106050D03*
X802499Y1097566D03*
X798499D03*
X783333Y1157392D03*
Y1161892D03*
X780333Y1165892D03*
X775833D03*
X771333Y1161892D03*
Y1165892D03*
X808299Y1175850D03*
X806599Y1189750D03*
X803599Y1211050D03*
X831499Y1209550D03*
Y1200550D03*
Y1181550D03*
X789499Y1225050D03*
X791499Y1206550D03*
X790999Y1194550D03*
Y1175550D03*
X839999Y1157550D03*
X826199Y1294450D03*
X828199Y1267850D03*
X788999Y1278150D03*
X791999Y1294450D03*
X808199Y1290350D03*
Y1275850D03*
X810199Y1248350D03*
Y1257350D03*
Y1229350D03*
X829499Y1242550D03*
Y1228050D03*
X789499Y1257050D03*
Y1239550D03*
X825500Y1379000D03*
X831499Y1324950D03*
X795299Y1326650D03*
X822199Y1335250D03*
X819199Y1353550D03*
X798299Y1344250D03*
X779399Y1361850D03*
X762499Y1335550D03*
Y1353050D03*
X799999Y1340550D03*
Y1358050D03*
X806499Y1390550D03*
X803299Y1426650D03*
X773999Y1393450D03*
X763399Y1401450D03*
X781999Y1434650D03*
X805899Y1464250D03*
X771399Y1474550D03*
X806499Y1408050D03*
X834499Y1397550D03*
X836600Y1416500D03*
X769300Y1488100D03*
X779000Y1488400D03*
X786500Y1488600D03*
X801300Y1489000D03*
X770999Y1500050D03*
X780499D03*
X839499Y1523550D03*
X773499Y1509050D03*
X769499D03*
X786999Y1506550D03*
X809245Y1518722D03*
Y1508722D03*
Y1503722D03*
X795999Y1518550D03*
Y1514050D03*
Y1509550D03*
Y1504550D03*
X808999Y1513550D03*
X785827Y1561296D03*
Y1565796D03*
X782827Y1569796D03*
X778327D03*
X773327Y1565796D03*
X773827Y1569796D03*
X813300Y1604100D03*
X827199Y1622750D03*
X841499Y1638950D03*
X803599Y1618350D03*
X826499Y1609050D03*
X825999Y1578050D03*
X839899Y1562050D03*
X829200Y1719800D03*
X824100Y1719900D03*
X819400Y1721900D03*
X837199Y1660550D03*
X814599Y1642650D03*
X776999Y1647650D03*
X797299Y1646650D03*
X802899Y1670550D03*
X839199Y1683550D03*
X808899Y1698450D03*
X779999Y1717050D03*
X770399Y1699650D03*
X765099Y1664950D03*
X823499Y1693050D03*
Y1702050D03*
Y1674050D03*
X782999Y1687050D03*
X783499Y1699050D03*
X782999Y1668050D03*
X819200Y1727100D03*
X808299Y1755250D03*
X794499Y1734550D03*
X770099Y1730350D03*
X779899Y1748150D03*
X787900Y1758800D03*
X765600Y1756800D03*
X827999Y1791550D03*
X767159Y1792364D03*
X829799Y1856350D03*
X809299D03*
X791799Y1855850D03*
X801099Y1844750D03*
X785599D03*
X765099D03*
X780799Y1888850D03*
X763299Y1888350D03*
X833100Y1878500D03*
X806199Y1879250D03*
X788699Y1878750D03*
X769199Y1879250D03*
X833199Y1868450D03*
X818900Y1870800D03*
X797199Y1868450D03*
X779699Y1867950D03*
X779399Y1855850D03*
X763899D03*
X773999Y1923550D03*
X767999Y1923050D03*
X774499Y1930050D03*
X768999D03*
X783814Y1967213D03*
Y1971713D03*
X783499Y1907050D03*
X774499Y1908050D03*
X765999D03*
X838999Y1928550D03*
X790499Y1913050D03*
X775999Y1916050D03*
X840999Y1970550D03*
X768499Y1917550D03*
X795526Y1909696D03*
X795493Y1913696D03*
X795501Y1917696D03*
X795499Y1922050D03*
X807997Y1922865D03*
X808005Y1918865D03*
X807936Y1914865D03*
Y1910365D03*
X784016Y1975708D03*
X775814Y1975699D03*
X771814Y1975713D03*
X813599Y1979950D03*
X789299Y1983850D03*
X829499Y1980250D03*
X829999Y1987550D03*
X812499Y1987050D03*
X792999Y1987550D03*
X777499D03*
X902999Y22050D03*
X917499Y21550D03*
X909499D03*
X902499Y35050D03*
X909999Y35550D03*
X916499Y36050D03*
X844799Y19850D03*
X860799Y24150D03*
X885999Y21150D03*
X855999Y6550D03*
X871499D03*
X890999Y6050D03*
X908499Y6550D03*
X923999Y6050D03*
X854499Y39550D03*
X865499D03*
X883999Y39050D03*
X904999Y61550D03*
Y67550D03*
X905499Y56550D03*
X890700Y132500D03*
X872100Y132700D03*
X854300Y132600D03*
X891999Y146050D03*
X843499Y82550D03*
X855499Y82050D03*
X876999D03*
X867499D03*
X845999Y111050D03*
X886499Y99550D03*
Y104550D03*
X890459Y100116D03*
X890499Y104550D03*
X865499Y125550D03*
X875499D03*
X856499Y71050D03*
X881499Y70550D03*
X866999D03*
X904499Y74050D03*
X906999Y224150D03*
X887400Y233555D03*
X871786Y233924D03*
Y218924D03*
Y203924D03*
X907999Y264150D03*
X906999Y243150D03*
X906399Y314250D03*
Y295250D03*
X863999Y313550D03*
X887400Y259700D03*
X879878Y247724D03*
X907399Y335250D03*
X875799Y386250D03*
X904999Y385050D03*
Y370550D03*
X854499Y387550D03*
Y373050D03*
X858400Y352300D03*
X847999Y352550D03*
X870600Y346700D03*
X876799Y426250D03*
X875799Y405250D03*
X884399Y462450D03*
Y443450D03*
X905499Y462050D03*
X904499Y441050D03*
Y422050D03*
X904999Y402550D03*
X854999Y464550D03*
X853999Y443550D03*
X854499Y405050D03*
X853999Y424550D03*
X861199Y546050D03*
X860199Y525050D03*
X885399Y483450D03*
X914699Y524650D03*
X913699Y503650D03*
Y484650D03*
X860699Y565550D03*
X898999Y622050D03*
Y604550D03*
X860499Y607550D03*
X861800Y591200D03*
X918999Y641550D03*
X870719Y609705D03*
X894000Y642400D03*
X870719Y639705D03*
X870773Y624705D03*
X903999Y574378D03*
X866499Y724550D03*
X895999Y720050D03*
Y702550D03*
X900999Y670050D03*
Y652550D03*
X918499Y712050D03*
X918999Y673550D03*
X918499Y693050D03*
X918999Y656050D03*
X887401Y665000D03*
X881200Y652100D03*
X859999Y713050D03*
X871385Y719436D03*
X871786Y709482D03*
X871499Y689436D03*
X871786Y679436D03*
X860796Y678632D03*
X921399Y796350D03*
X921899Y776850D03*
Y759350D03*
Y744850D03*
X884499Y799050D03*
Y781550D03*
Y767050D03*
X859999Y799550D03*
Y782050D03*
Y767550D03*
X919499Y733050D03*
X856299Y753150D03*
X846799Y754150D03*
X865000Y752100D03*
X889699Y876050D03*
X847799Y828250D03*
X857099Y873450D03*
X920399Y886850D03*
Y869350D03*
Y854850D03*
X922399Y836350D03*
X921399Y815350D03*
X898499Y862050D03*
Y844550D03*
Y830050D03*
X873999Y862550D03*
Y845050D03*
Y830550D03*
X886999Y947250D03*
Y907350D03*
X867199Y941350D03*
X866199Y920350D03*
Y901350D03*
X850999Y962550D03*
Y943550D03*
X919899Y925350D03*
X920899Y946350D03*
X919899Y906350D03*
X851999Y983550D03*
X921499Y1031050D03*
X920999Y1050550D03*
X921499Y1013550D03*
Y999050D03*
X870468Y1030227D03*
X880033Y1058592D03*
X886919Y1044478D03*
X870298Y1045227D03*
X870777Y1014948D03*
X921999Y1090550D03*
X920999Y1069550D03*
X887400Y1070600D03*
X859999Y1118550D03*
X841999D03*
X845799Y1190450D03*
X849799Y1199750D03*
X846499Y1170450D03*
X897299Y1182450D03*
X887999Y1209350D03*
X871399Y1201850D03*
Y1210850D03*
Y1182850D03*
X892499Y1224550D03*
X851999Y1218550D03*
X856400Y1157700D03*
X848999Y1158050D03*
X863300Y1153800D03*
X872099Y1268150D03*
X871399Y1291450D03*
X860099Y1295450D03*
X869399Y1243850D03*
Y1229350D03*
X890499Y1285550D03*
Y1271050D03*
X892499Y1252550D03*
Y1243550D03*
X850499Y1300050D03*
Y1282550D03*
Y1268050D03*
X852499Y1249550D03*
X851999Y1237550D03*
X875399Y1322650D03*
X868499Y1392550D03*
X890999Y1336550D03*
Y1354050D03*
X841999Y1341050D03*
Y1358550D03*
X873499Y1356050D03*
X894499Y1423550D03*
Y1441050D03*
X868499Y1410050D03*
X886913Y1449010D03*
X879727Y1463696D03*
X871836Y1450460D03*
Y1435460D03*
Y1420460D03*
X914599Y1521650D03*
X910899Y1549250D03*
X894499Y1522050D03*
Y1539550D03*
X895499Y1488050D03*
X902759Y1509585D03*
X861999Y1522550D03*
X843999Y1523550D03*
X887499Y1476050D03*
X865300Y1557700D03*
X923599Y1634350D03*
X909700Y1576400D03*
X907500Y1604000D03*
X908899Y1630050D03*
X868099Y1635650D03*
X887299Y1620050D03*
X886900Y1604100D03*
X873099Y1572550D03*
X850099Y1572250D03*
X849900Y1605100D03*
X852499Y1621350D03*
X866499Y1603050D03*
Y1612050D03*
X864000Y1578200D03*
X858400Y1561900D03*
X850499Y1562050D03*
X879200Y1698700D03*
X879900Y1709300D03*
X883900Y1709500D03*
X855350Y1703201D03*
X914899Y1657550D03*
X922599Y1682150D03*
X903599Y1686850D03*
X895999Y1661250D03*
X877699Y1646650D03*
X855799Y1658250D03*
X882999Y1678250D03*
X864099Y1683550D03*
X842799Y1701150D03*
X875900Y1709500D03*
X902900Y1709800D03*
X882200Y1744800D03*
X886400Y1744400D03*
X842500Y1799000D03*
X892700Y1727800D03*
X879399Y1798150D03*
X911299Y1800850D03*
X864000Y1748000D03*
X866699Y1770950D03*
X853799Y1790850D03*
X844499Y1788050D03*
X892700Y1736500D03*
X904814Y1789113D03*
X863099Y1813150D03*
X903299Y1814750D03*
X894999Y1829050D03*
X922899Y1853650D03*
X905299Y1852650D03*
X900299Y1876950D03*
X842199Y1879250D03*
X914999Y1887050D03*
Y1868050D03*
X862499Y1823550D03*
X854977Y1818994D03*
X887401Y1881500D03*
X894000Y1868452D03*
X887499Y1855550D03*
X869999Y1855972D03*
X871836Y1840972D03*
X869634Y1826876D03*
X864414Y1940050D03*
X914899Y1912450D03*
X916599Y1942650D03*
X897599Y1938750D03*
X914899Y1972250D03*
X873399Y1963650D03*
X904299Y1954950D03*
X897299Y1904150D03*
X907599Y1930050D03*
X915499Y1899050D03*
X861414Y1928550D03*
X843999D03*
X856999Y1970050D03*
X849999Y1970550D03*
X865200Y1968000D03*
X879399Y1974550D03*
X850499Y1977950D03*
X868699Y1983250D03*
X921499Y1986550D03*
X901999Y1987050D03*
X864999D03*
X849499D03*
X884499Y1986550D03*
X974699Y64650D03*
X977399Y44050D03*
X954799Y17850D03*
X974699Y21450D03*
X991399Y22450D03*
X1002699Y40050D03*
X991999Y56050D03*
X941499Y6550D03*
X960999D03*
X976499D03*
X995999Y6050D03*
X967499Y47050D03*
Y56050D03*
Y64050D03*
X945499Y33550D03*
X940499Y33050D03*
X929999Y32550D03*
X928499Y51550D03*
X943499Y48050D03*
Y55050D03*
X928999Y56050D03*
X928499Y60550D03*
X928999Y65550D03*
X942999Y61550D03*
Y66550D03*
X983099Y83650D03*
X1005299Y71350D03*
X977699Y109150D03*
X994399Y101250D03*
X981099Y123450D03*
X939199Y142050D03*
X968399Y137150D03*
X967999Y73050D03*
Y82050D03*
X943499Y72550D03*
Y78050D03*
X988699Y174350D03*
X967399Y180350D03*
X956099Y181350D03*
X958799Y167350D03*
X1004799Y231450D03*
X1005299Y211950D03*
Y194450D03*
Y179950D03*
X952799Y231150D03*
Y213650D03*
Y199150D03*
X982999Y203550D03*
Y221050D03*
Y189050D03*
X932499Y223550D03*
Y206050D03*
Y191550D03*
X1005299Y305450D03*
Y290950D03*
X1005799Y271450D03*
X1004799Y250450D03*
X952799Y310150D03*
X953299Y290650D03*
X952299Y269650D03*
Y250650D03*
X983999Y316050D03*
Y301550D03*
X933499Y304050D03*
X983499Y280550D03*
X982499Y259550D03*
Y240550D03*
X932999Y283050D03*
X931999Y262050D03*
Y243050D03*
X1005799Y382450D03*
X1004799Y361450D03*
X1005299Y322950D03*
X1004799Y342450D03*
X952299Y380650D03*
X952799Y342150D03*
X952299Y361650D03*
X952799Y324650D03*
X984499Y393050D03*
X983499Y372050D03*
Y353050D03*
X983999Y333550D03*
X933999Y395550D03*
X932999Y374550D03*
X933499Y336050D03*
X932999Y355550D03*
X933499Y318550D03*
X966199Y473350D03*
X1000699Y482350D03*
Y463350D03*
X954799Y451650D03*
Y434150D03*
Y419650D03*
X953299Y401650D03*
X983499Y464050D03*
X983999Y427050D03*
Y444550D03*
Y412550D03*
X933499Y447050D03*
X932999Y466550D03*
X933499Y429550D03*
Y415050D03*
X967199Y513350D03*
X966199Y492350D03*
X1001699Y503350D03*
X1003499Y546350D03*
X1003999Y526850D03*
X951299Y560150D03*
Y541150D03*
X951799Y521650D03*
Y504150D03*
Y489650D03*
X985999Y536550D03*
Y554050D03*
Y522050D03*
X935499Y556550D03*
Y539050D03*
Y524550D03*
X984499Y504050D03*
X983499Y483050D03*
X933999Y506550D03*
X932999Y485550D03*
X967799Y606350D03*
X966799Y585350D03*
Y566350D03*
X1005999Y636350D03*
Y618850D03*
X1004499Y586350D03*
X1005999Y604350D03*
X1003499Y565350D03*
X950299Y631650D03*
Y614150D03*
Y599650D03*
X952299Y581150D03*
X969499Y639050D03*
X986499Y613550D03*
X985499Y592550D03*
Y573550D03*
X935999Y616050D03*
X934999Y595050D03*
Y576050D03*
X949799Y670150D03*
X950799Y691150D03*
X949799Y651150D03*
X969999Y730550D03*
X968999Y709550D03*
Y690550D03*
X969499Y653550D03*
Y671050D03*
Y795750D03*
X969999Y776250D03*
Y758750D03*
Y744250D03*
X994499Y803550D03*
Y784550D03*
X994999Y747550D03*
Y765050D03*
Y733050D03*
X943999Y806050D03*
X944499Y767550D03*
X943999Y787050D03*
X944499Y750050D03*
Y735550D03*
X970499Y879750D03*
Y862250D03*
Y847750D03*
Y835750D03*
X969499Y814750D03*
X992999Y894550D03*
X993499Y857550D03*
Y875050D03*
Y843050D03*
X942999Y877550D03*
Y860050D03*
Y845550D03*
X995499Y824550D03*
X944999Y827050D03*
X994499Y973550D03*
Y956050D03*
Y941550D03*
X949299Y977450D03*
X970999Y939250D03*
X969999Y918250D03*
Y899250D03*
X993999Y934550D03*
X992999Y913550D03*
X943499Y937050D03*
X942499Y916050D03*
Y897050D03*
X994999Y1033050D03*
Y1045050D03*
X993999Y1012050D03*
Y993050D03*
X948799Y1047950D03*
Y1028950D03*
X949299Y1009450D03*
Y991950D03*
X971499Y1048050D03*
X971999Y1011050D03*
Y1028550D03*
Y996550D03*
X949799Y1068950D03*
Y1080950D03*
X998599Y1128450D03*
Y1110950D03*
Y1096450D03*
X950699Y1139750D03*
Y1122250D03*
Y1107750D03*
X975999Y1115550D03*
Y1133050D03*
Y1101050D03*
X925499Y1135550D03*
Y1118050D03*
Y1103550D03*
X972499Y1088050D03*
X971499Y1067050D03*
X999099Y1214450D03*
Y1199950D03*
Y1187950D03*
X998099Y1147950D03*
Y1166950D03*
X951199Y1225750D03*
Y1211250D03*
Y1199250D03*
X950199Y1159250D03*
Y1178250D03*
X976499Y1219050D03*
Y1204550D03*
X925999Y1221550D03*
Y1207050D03*
X976499Y1192550D03*
X975499Y1171550D03*
Y1152550D03*
X925999Y1195050D03*
X924999Y1174050D03*
Y1155050D03*
X999599Y1291450D03*
X998599Y1270450D03*
Y1251450D03*
X999099Y1231950D03*
X951699Y1302750D03*
X950699Y1281750D03*
Y1262750D03*
X951199Y1243250D03*
X976999Y1296050D03*
X975999Y1275050D03*
Y1256050D03*
X976499Y1236550D03*
X926499Y1298550D03*
X925499Y1277550D03*
X925999Y1239050D03*
X925499Y1258550D03*
X975100Y1342600D03*
X1000700Y1358100D03*
X996500Y1324800D03*
X952499Y1361850D03*
X944000Y1391900D03*
X943799Y1380850D03*
Y1342950D03*
X965099Y1324350D03*
X928499Y1325350D03*
X976499Y1377050D03*
Y1362550D03*
X925999Y1379550D03*
Y1365050D03*
X973500Y1474000D03*
X971500Y1467500D03*
X971700Y1457800D03*
Y1462300D03*
X972000Y1442000D03*
Y1437500D03*
X971700Y1448300D03*
Y1452800D03*
X962500Y1436500D03*
Y1441000D03*
X952800Y1437500D03*
Y1442000D03*
X962000Y1466500D03*
X966000Y1475000D03*
X952300Y1467500D03*
X958800Y1472500D03*
X962200Y1447300D03*
Y1451800D03*
X952500Y1448300D03*
Y1452800D03*
X962200Y1456800D03*
Y1461300D03*
X952500Y1457800D03*
Y1462300D03*
X992500Y1397300D03*
X964400Y1409700D03*
X946700Y1426500D03*
X994200Y1421500D03*
X924999Y1471050D03*
X926499Y1456550D03*
X925499Y1435550D03*
X925999Y1397050D03*
X925499Y1416550D03*
X972549Y1502300D03*
Y1506800D03*
X973500Y1483000D03*
Y1478500D03*
X973200Y1488300D03*
X972700Y1497300D03*
X966000Y1479500D03*
Y1484000D03*
X958800Y1477000D03*
Y1481500D03*
X965700Y1489300D03*
X960200Y1495300D03*
X958500Y1486800D03*
X951500Y1495300D03*
X960049Y1500300D03*
X951349D03*
X960049Y1504800D03*
X951349D03*
X973200Y1516400D03*
X972500Y1529100D03*
X966600D03*
X961400Y1528700D03*
X961900Y1522400D03*
X967100Y1522800D03*
X973000D03*
X962100Y1516000D03*
X967300Y1516400D03*
X972700Y1534800D03*
X972000Y1547500D03*
X966100D03*
X960900Y1547100D03*
X961400Y1540800D03*
X966600Y1541200D03*
X972500D03*
X961600Y1534400D03*
X966800Y1534800D03*
X972700Y1553300D03*
X961600Y1552900D03*
X966800Y1553300D03*
X944000Y1511300D03*
X943199Y1531650D03*
X924499Y1541550D03*
X924999Y1503050D03*
X924499Y1522550D03*
X924999Y1485550D03*
X972000Y1566000D03*
X966100D03*
X960900Y1565600D03*
X961400Y1559300D03*
X966600Y1559700D03*
X972500D03*
X973000Y1572800D03*
X972300Y1585500D03*
X966400D03*
X961200Y1585100D03*
X961700Y1578800D03*
X966900Y1579200D03*
X972800D03*
X961900Y1572400D03*
X967100Y1572800D03*
X972400Y1592000D03*
X966500D03*
X961300Y1591600D03*
X972200Y1598400D03*
X966300D03*
X961100Y1598000D03*
X960600Y1604300D03*
X971700Y1604700D03*
X965800D03*
X944499Y1632650D03*
X925599Y1612050D03*
X933199Y1577550D03*
X925499Y1562550D03*
X950100Y1626100D03*
X989999Y1718050D03*
X958799Y1715750D03*
X957799Y1646950D03*
X955499Y1690850D03*
X941499Y1679550D03*
X940499Y1656950D03*
X931499Y1702050D03*
X941800Y1787700D03*
X934200Y1793500D03*
X993299Y1734350D03*
X994999Y1748950D03*
X976600Y1757100D03*
X965349Y1742000D03*
X949799Y1756250D03*
X976399Y1772250D03*
X954499Y1783550D03*
X941499Y1776250D03*
X932199Y1801850D03*
X971000Y1803000D03*
X999999Y1775250D03*
X976399Y1791150D03*
X993499Y1805550D03*
X928000Y1818500D03*
X1003599Y1846650D03*
X995699Y1858950D03*
X971500Y1871500D03*
X937199Y1869950D03*
X993499Y1824550D03*
Y1833550D03*
X987999Y1971950D03*
Y1949050D03*
X1000999Y1946350D03*
X991999Y1915750D03*
X966799Y1892150D03*
X974699Y1914450D03*
X945199Y1946350D03*
X955799Y1951950D03*
X954099Y1915450D03*
X938199Y1917150D03*
X1002500Y1953500D03*
X1001599Y1921450D03*
X992299Y1929050D03*
X989999Y1962650D03*
X980999Y1933350D03*
X947499Y1936050D03*
X946199Y1966650D03*
X937499Y1893850D03*
X971499Y1956050D03*
Y1965050D03*
Y1937050D03*
X930999Y1950050D03*
X931499Y1962050D03*
X930999Y1931050D03*
X955499Y1893050D03*
Y1902050D03*
X953799Y1977950D03*
X930199Y1979550D03*
X1005000Y1980500D03*
X994999Y1986550D03*
X973999D03*
X956499Y1986050D03*
X936999Y1986550D03*
X1022000Y15500D03*
X1013499Y6550D03*
X1020499Y50550D03*
X1020999Y33050D03*
X1010599Y115550D03*
X1020499Y122550D03*
X1020999Y105050D03*
Y85550D03*
Y70050D03*
X1021499Y141050D03*
X1020999Y230550D03*
X1021499Y213050D03*
Y193550D03*
Y178050D03*
X1020999Y158550D03*
Y304550D03*
Y289050D03*
X1020499Y269550D03*
X1020999Y252050D03*
X1020499Y341550D03*
X1020999Y324050D03*
X1020499Y391550D03*
X1020999Y374050D03*
X1007299Y432450D03*
Y414950D03*
Y400450D03*
X1020499Y463550D03*
X1020999Y446050D03*
Y426550D03*
Y411050D03*
X1021999Y558550D03*
Y539050D03*
Y523550D03*
X1021499Y504050D03*
X1021999Y486550D03*
X1021499Y576050D03*
X1020999Y642550D03*
X1020499Y623050D03*
X1020999Y605550D03*
X1020499Y695050D03*
X1020999Y677550D03*
Y658050D03*
Y720050D03*
X1020499Y809550D03*
X1020999Y792050D03*
Y772550D03*
Y757050D03*
X1020499Y737550D03*
Y880550D03*
Y865050D03*
X1019999Y845550D03*
X1020499Y828050D03*
X1019999Y917550D03*
X1020499Y900050D03*
X1019999Y971050D03*
X1019499Y951550D03*
X1019999Y934050D03*
Y986550D03*
Y1058550D03*
Y1043050D03*
X1019499Y1023550D03*
X1019999Y1006050D03*
X1020499Y1134050D03*
Y1118550D03*
X1019999Y1099050D03*
X1020499Y1081550D03*
X1019499Y1198550D03*
Y1183050D03*
X1018999Y1163550D03*
X1019499Y1146050D03*
X1016999Y1219050D03*
X1016499Y1301050D03*
Y1236550D03*
X1016999Y1256050D03*
Y1271550D03*
X1023300Y1344400D03*
X1024300Y1365200D03*
X1022599Y1322950D03*
X1024300Y1393600D03*
X1008599Y1716050D03*
X1022299Y1715750D03*
X1008999Y1702450D03*
X1016899Y1731650D03*
X1026899Y1768550D03*
X1020299Y1746650D03*
X1015299Y1765950D03*
X1009999Y1797450D03*
X1022499Y1802050D03*
X1022999Y1784550D03*
X1011299Y1860650D03*
X1007599Y1818450D03*
X1022999Y1821550D03*
Y1837050D03*
X1020499Y1877550D03*
X1020999Y1860050D03*
Y1912550D03*
Y1897050D03*
X1017499Y1954550D03*
X1017999Y1937050D03*
Y1987050D03*
X1023000Y1973000D03*
X1281550Y1871750D03*
G54D12*
X9843Y153168D03*
Y265767D03*
Y353144D03*
Y717711D03*
Y762617D03*
Y875216D03*
Y1137420D03*
Y1250019D03*
Y1337396D03*
Y1701963D03*
Y1746869D03*
Y1859468D03*
X1281550Y1731250D03*
G54D13*
X8750Y1086250D03*
X8499Y1937550D03*
X5303Y1947050D03*
X11703Y1951946D03*
X93999Y58550D03*
X92900Y66128D03*
X89800Y132400D03*
X92999Y86128D03*
Y96128D03*
X74499Y84050D03*
Y80650D03*
X86899Y130567D03*
X86599Y126750D03*
X74999Y74050D03*
Y70550D03*
X78700Y70700D03*
Y74200D03*
X15750Y102250D03*
X41999Y200050D03*
X65999Y216050D03*
X95350Y204550D03*
X89800Y208550D03*
X24300Y247300D03*
X29699Y388484D03*
X29599Y382884D03*
X29999Y398684D03*
X23499Y397579D03*
X23399Y373931D03*
Y389679D03*
X23499Y381831D03*
X26299Y383854D03*
Y387629D03*
X28100Y374000D03*
X26492Y439350D03*
X26599Y442749D03*
X26299Y399601D03*
Y403376D03*
Y478404D03*
X26899Y454850D03*
X26515Y481798D03*
X45800Y405200D03*
X26799Y458497D03*
X26486Y462648D03*
X26499Y466250D03*
X64403Y471046D03*
X64397Y474446D03*
X26524Y426720D03*
X26399Y423322D03*
X29899Y404384D03*
X28900Y429200D03*
X29365Y421169D03*
X29500Y460800D03*
X28700Y451900D03*
X28800Y436700D03*
X28700Y445700D03*
X68000Y475600D03*
X67800Y469900D03*
X23499Y468447D03*
X23399Y476295D03*
Y444799D03*
X23499Y452699D03*
X23399Y460547D03*
Y429051D03*
X23499Y436951D03*
X23600Y405700D03*
X77499Y469550D03*
X61400Y452600D03*
X35900Y412600D03*
X65000Y455500D03*
X28900Y417800D03*
X39217Y554750D03*
X42867Y548450D03*
X43099Y555850D03*
X33699Y561850D03*
X46299Y552950D03*
X36499Y517775D03*
Y521550D03*
X26399Y501966D03*
Y505741D03*
X64600Y486300D03*
X64700Y489700D03*
X33307Y557938D03*
X26199Y547176D03*
X93200Y510500D03*
X83700Y529500D03*
X28600Y508500D03*
X35300Y524800D03*
X38400Y514900D03*
X88999Y538050D03*
X68900Y490600D03*
X68700Y485200D03*
X28600Y499300D03*
X26900Y532800D03*
X63499Y538550D03*
Y533050D03*
X22800Y539600D03*
X23499Y515691D03*
X23399Y523539D03*
X23499Y531439D03*
X23399Y492043D03*
X23499Y499943D03*
X23399Y507791D03*
X23499Y484195D03*
X77999Y493050D03*
X77499Y502550D03*
X29999Y557150D03*
X26599Y525648D03*
X95500Y513400D03*
X26599Y529302D03*
X60003Y534150D03*
X86199Y536025D03*
X59999Y537550D03*
X86199Y532250D03*
X65599Y514250D03*
X49799Y559150D03*
X68000Y546500D03*
X72500Y545000D03*
X27199Y539600D03*
X42202Y608195D03*
X39600Y626984D03*
X41400Y611500D03*
X42709Y625607D03*
X38300Y633800D03*
X41500Y642800D03*
X27499Y620203D03*
Y623857D03*
X36499Y566350D03*
X37999Y611550D03*
X42599Y567850D03*
X32800Y578200D03*
X47543Y578340D03*
X44959Y575756D03*
X30712Y624971D03*
X29999Y640550D03*
X60076Y595777D03*
X55499Y595650D03*
X29819Y634951D03*
X26869Y616861D03*
X23399Y641649D03*
X23499Y618053D03*
X23799Y625950D03*
X23499Y633801D03*
X23999Y609250D03*
X22978Y588571D03*
X22699Y577950D03*
X22999Y565550D03*
X57800Y634300D03*
X34976Y619250D03*
X44900Y642800D03*
X26568Y635950D03*
Y639604D03*
X47101Y632355D03*
X28000Y578500D03*
X25581Y567763D03*
X47626Y611300D03*
X45701Y607700D03*
X27699Y573750D03*
X82499Y627050D03*
X26800Y611500D03*
X41500Y635000D03*
X52500D03*
X48999Y642900D03*
X81251Y607249D03*
Y619251D03*
X28808Y593150D03*
X28700Y596549D03*
X32200Y603710D03*
X31598Y607102D03*
X80499Y664550D03*
X30999Y656250D03*
X29999Y694550D03*
X30999Y650550D03*
X81999Y668050D03*
X74499Y662050D03*
X25999Y694870D03*
X23999Y689050D03*
X23499Y665297D03*
X23699Y673150D03*
X23499Y681045D03*
Y649549D03*
X23725Y657471D03*
X78499Y654050D03*
X26737Y651957D03*
X26999Y656550D03*
X27687Y667447D03*
Y671101D03*
X76999Y664550D03*
X27700Y682700D03*
X50410Y695801D03*
X50300Y699200D03*
X44046Y799554D03*
X32800Y803050D03*
X46887Y803413D03*
X37416Y799033D03*
X37099Y811350D03*
X51100Y806300D03*
X49900Y813200D03*
X56281Y801350D03*
X27299Y783550D03*
X35300Y789375D03*
X90700Y792900D03*
X35559Y795112D03*
X45100Y793100D03*
X37216Y807951D03*
X76540Y850938D03*
X29299Y836901D03*
X75500Y847700D03*
X49300Y836500D03*
X46700Y820100D03*
X40400Y840792D03*
X89000Y816500D03*
X48346Y844529D03*
X58699Y837250D03*
X26299Y815050D03*
X92999Y868550D03*
X92499Y876550D03*
X68860Y838706D03*
X90000Y826000D03*
X54074Y815750D03*
X69499Y842950D03*
X62405Y820300D03*
X63499Y843050D03*
X90500Y831500D03*
X31699Y814350D03*
X65500Y817700D03*
X23299Y863050D03*
X26662Y861550D03*
X39649Y822000D03*
X80500Y817000D03*
X74220Y854150D03*
X72362Y849550D03*
X25000Y858100D03*
X46576Y832951D03*
X29600Y854000D03*
X24000Y853500D03*
X89400Y935400D03*
X89499Y942850D03*
X94999Y901550D03*
X85999Y940429D03*
X86399Y937050D03*
X29000Y896500D03*
X72000Y1013400D03*
X63273Y1023974D03*
X90000Y993100D03*
X92600Y996100D03*
X80699Y1004450D03*
Y1000450D03*
X20400Y1048300D03*
X66499Y1025050D03*
X75900Y1019100D03*
X63500Y1029600D03*
X88000Y1008500D03*
X75500Y1012261D03*
X80000Y1090500D03*
X80500Y1097550D03*
Y1104500D03*
X76999Y1196550D03*
X21817Y1156317D03*
X78499Y1273550D03*
X78613Y1282664D03*
X78779Y1302664D03*
X91279Y1340642D03*
X89999Y1348050D03*
X27499Y1387550D03*
X24499Y1389663D03*
X22851Y1374169D03*
X22999Y1366050D03*
X23700Y1354600D03*
X23499Y1381500D03*
X78779Y1312664D03*
X86165Y1339050D03*
X25507Y1372045D03*
X25558Y1368447D03*
X86890Y1346635D03*
Y1342860D03*
X28499Y1391050D03*
X32333Y1389383D03*
X20999Y1352050D03*
Y1320550D03*
X77758Y1357742D03*
X25000D03*
X30378Y1462518D03*
X33915Y1462681D03*
X32094Y1448448D03*
X28697Y1448296D03*
X33000Y1393000D03*
X33400Y1408100D03*
X36198Y1446749D03*
X26800Y1443800D03*
X30600Y1415100D03*
X30999Y1438050D03*
X27999Y1430050D03*
X29100Y1459200D03*
X34200Y1466200D03*
X23028Y1468579D03*
X23499Y1460550D03*
X22999Y1453050D03*
X23499Y1445050D03*
X22999Y1437050D03*
X23999Y1429050D03*
X23499Y1421550D03*
X23999Y1413550D03*
X32451Y1411468D03*
X28999Y1411550D03*
X33206Y1432352D03*
X30499Y1434550D03*
X30500Y1395500D03*
X76000Y1431100D03*
X34896Y1555730D03*
X34099Y1497550D03*
X30499D03*
X80043Y1544691D03*
X83932Y1544705D03*
X29631Y1533063D03*
X31999Y1517846D03*
Y1521500D03*
X46700Y1546793D03*
X34465Y1481683D03*
X30999Y1482050D03*
X44299Y1550950D03*
X96200Y1550100D03*
X32700Y1485200D03*
X28999Y1478050D03*
X27100Y1494300D03*
X34900Y1501000D03*
X35400Y1522200D03*
X35999Y1514550D03*
X29600Y1515300D03*
X24423Y1527123D03*
X22999Y1500050D03*
Y1515550D03*
X23799Y1508050D03*
X24499Y1492050D03*
X23599Y1476350D03*
X23277Y1484050D03*
X25247Y1546912D03*
X37999Y1530900D03*
X38500Y1534600D03*
X32099Y1535550D03*
X30115Y1511900D03*
X33512Y1512051D03*
X90324Y1538800D03*
X26705Y1534795D03*
X30199Y1545450D03*
X24199Y1523700D03*
X79000Y1555500D03*
X82429D03*
X36340Y1558809D03*
X78600Y1561900D03*
X29499Y1630050D03*
X75000Y1561800D03*
X28899Y1613524D03*
X42199Y1601050D03*
X38208Y1569841D03*
X25521Y1563350D03*
X30520Y1572049D03*
X32299Y1613524D03*
X34599Y1595300D03*
X24900Y1569500D03*
X31149Y1568300D03*
X26999Y1610550D03*
X34884Y1615734D03*
X32199Y1633124D03*
X34816Y1630953D03*
X22999Y1626050D03*
X23499Y1634050D03*
Y1618050D03*
X22699Y1594224D03*
X23499Y1610050D03*
Y1602050D03*
X23608Y1572653D03*
X24323Y1559950D03*
X31099Y1595350D03*
X32663Y1628181D03*
X27123Y1572205D03*
X33599Y1600200D03*
X74800Y1584700D03*
X74700Y1574600D03*
X39000Y1573500D03*
X89373Y1561073D03*
X85600Y1561500D03*
X80400Y1571766D03*
X82329Y1568117D03*
X31999Y1661127D03*
X28600Y1661039D03*
X29626Y1645002D03*
X33026Y1645051D03*
X95499Y1665418D03*
X33100Y1648500D03*
X47400Y1721700D03*
X34699Y1663300D03*
X27499Y1657050D03*
X26785Y1642089D03*
X22999Y1665550D03*
X92873Y1708176D03*
X24244Y1681868D03*
X22864Y1673550D03*
X23499Y1657050D03*
X23999Y1649550D03*
X23415Y1641634D03*
X92479Y1718176D03*
X78100Y1688189D03*
X92900Y1678176D03*
X93999Y1703050D03*
X74500Y1692000D03*
X21600Y1702900D03*
X32700Y1673300D03*
X32494Y1669706D03*
X29100Y1669500D03*
X30274Y1787238D03*
X85599Y1797350D03*
X38878Y1799571D03*
X47899Y1798650D03*
X36300Y1805123D03*
X35675Y1783450D03*
X39324Y1780623D03*
X39000Y1750800D03*
X43751Y1780559D03*
X42275Y1754000D03*
X48049Y1791450D03*
X40400Y1735600D03*
X47900Y1731300D03*
X47800Y1740500D03*
X89306Y1746856D03*
X89499Y1753575D03*
X85341Y1752245D03*
X85194Y1748848D03*
X46999Y1779550D03*
X37699Y1789850D03*
X46199Y1783050D03*
X74400Y1778100D03*
X38094Y1785840D03*
X41200Y1747050D03*
X42199Y1792250D03*
X37574Y1794050D03*
X45799Y1757650D03*
X46799Y1794900D03*
X47440Y1761391D03*
X31811Y1790271D03*
X47400Y1765250D03*
X43559Y1767884D03*
X40478Y1795820D03*
X32099Y1797150D03*
X47604Y1769005D03*
X45782Y1771877D03*
X47499Y1775350D03*
X45877Y1728477D03*
Y1724823D03*
X47000Y1737100D03*
X43600D03*
X28550Y1828153D03*
X29599Y1844350D03*
X29899Y1821050D03*
X34099Y1822850D03*
X60449Y1842550D03*
X80099Y1817250D03*
X28123Y1831527D03*
X35876Y1812350D03*
X34129Y1815267D03*
X86649Y1817100D03*
X61009Y1822340D03*
X36532Y1825352D03*
X36399Y1828750D03*
X26099Y1824950D03*
X25999Y1842550D03*
X46499Y1836550D03*
X47166Y1839884D03*
X80999Y1836550D03*
X90000Y1827900D03*
X43099Y1833850D03*
X39699D03*
X93500Y1827900D03*
X40500Y1863000D03*
X22367Y1836633D03*
X50299Y1946650D03*
X53999D03*
X42532Y1946783D03*
X44399Y1942250D03*
X38703Y1946754D03*
X34799Y1946750D03*
X46565Y1946703D03*
X44368Y1951450D03*
X45999Y1971450D03*
X28799Y1919060D03*
X14999Y1940050D03*
X15099Y1944050D03*
X50499Y1961550D03*
X14999Y1936050D03*
X17499Y1961050D03*
X43462Y1961160D03*
X32999Y1960555D03*
X23030Y1922038D03*
X25499Y1956050D03*
X42499Y1902550D03*
X48499Y1897050D03*
X26765Y1921945D03*
X57999Y1891050D03*
X31799Y1979050D03*
X112999Y124050D03*
X111790Y132259D03*
X152499Y149550D03*
X173499Y149050D03*
X175999Y82428D03*
X97499Y90050D03*
X115876Y125973D03*
Y130050D03*
X174999Y79050D03*
X175499Y86572D03*
X178999Y79050D03*
X176399Y94872D03*
X127999Y157050D03*
X114900Y177900D03*
X173500Y166315D03*
X154200Y168500D03*
X149400Y166400D03*
X149999Y243504D03*
Y239729D03*
X122397Y252688D03*
X122799Y249150D03*
X147099Y245350D03*
X124999Y246050D03*
X123300Y256000D03*
X157440Y283924D03*
Y303924D03*
Y313924D03*
X141499Y427550D03*
X165500Y416500D03*
X166500Y428500D03*
X153459Y427494D03*
X154101Y445550D03*
X141499Y423050D03*
X159600Y446399D03*
X152000Y520813D03*
X171722Y513827D03*
X163549Y517100D03*
X140940Y561800D03*
X150500Y545000D03*
X102100Y514900D03*
X163449Y521650D03*
X107526Y528996D03*
X104502Y530552D03*
X138999Y524213D03*
X173100Y483100D03*
X168453Y527949D03*
X160932Y549468D03*
X135499Y517550D03*
X107499Y497050D03*
X98900Y513400D03*
X172499Y491053D03*
X137899Y545451D03*
X176799Y493850D03*
X150750Y540416D03*
X109400Y543200D03*
X149000Y537500D03*
X106000Y543200D03*
X156500Y554000D03*
X138416Y553500D03*
X125499Y635550D03*
Y638950D03*
X127999Y645550D03*
X131400Y644600D03*
X144238Y645356D03*
X161000Y639100D03*
X124999Y643050D03*
X129000Y636600D03*
X128600Y640500D03*
X140900Y644000D03*
X134300Y646400D03*
X107000Y604800D03*
X105100Y600000D03*
X157000Y573851D03*
X141300Y565900D03*
X160824Y577000D03*
X144238Y649131D03*
X140400Y649800D03*
X158885Y679436D03*
Y689436D03*
X141500Y711000D03*
X158385Y719436D03*
X111200Y799450D03*
X110195Y809979D03*
X110500Y790200D03*
X110700Y795700D03*
X109831Y806598D03*
X109700Y803200D03*
X110202Y813379D03*
X154799Y838050D03*
X165499Y815550D03*
X110499Y834550D03*
X172660Y815731D03*
X174199Y841050D03*
X159500Y814700D03*
X169106Y815865D03*
X153900Y832200D03*
X98700Y842600D03*
Y822550D03*
X98000Y833500D03*
X163500Y937100D03*
X172500Y919294D03*
X108200Y963600D03*
X172000Y931600D03*
X106749Y934367D03*
X108441Y924705D03*
X160399Y922850D03*
X153499Y918550D03*
X108845Y931657D03*
X109099Y928250D03*
X171100Y935000D03*
X102100Y968500D03*
X99000Y965000D03*
X172000Y961000D03*
X152500Y960000D03*
X170250Y948500D03*
X154749Y968249D03*
X171000Y939500D03*
X123999Y1054050D03*
Y1050650D03*
X120100Y1053200D03*
X124100Y1047100D03*
X112699Y1058974D03*
X104600Y980500D03*
X154749Y979149D03*
X103200Y985364D03*
X104700Y989900D03*
X120749Y1093990D03*
X164700Y1085400D03*
X105499Y1080550D03*
X106718Y1076050D03*
X105999Y1085800D03*
X101499Y1072550D03*
X125900Y1091282D03*
X132499Y1094550D03*
X137100Y1084800D03*
X140800Y1076300D03*
X121500Y1083600D03*
X121100Y1075300D03*
X116249Y1102550D03*
X112999Y1103740D03*
X117499Y1079300D03*
X157700Y1114948D03*
X157600Y1124948D03*
X159000Y1083000D03*
X127000Y1113500D03*
X123999Y1102550D03*
X138600Y1124600D03*
X116700Y1063500D03*
X105600Y1069500D03*
X108999Y1102050D03*
X137481Y1077557D03*
X137477Y1081177D03*
X124423Y1077523D03*
Y1081177D03*
X106999Y1194550D03*
X102900Y1196050D03*
X103686Y1223863D03*
X103999Y1216863D03*
X127000Y1202000D03*
X148000Y1206000D03*
X106162Y1205702D03*
X114999Y1210363D03*
X130699Y1210653D03*
X118999Y1219050D03*
X123970Y1221573D03*
X119399Y1298113D03*
X101541Y1262607D03*
X116999Y1288050D03*
X101399Y1292550D03*
X107999Y1307713D03*
X120507Y1317050D03*
X116499Y1328013D03*
X120507Y1328096D03*
X135850Y1322250D03*
X143700Y1332500D03*
X101500Y1352000D03*
X113500D03*
X113000Y1341000D03*
X102000D03*
X107228Y1330552D03*
X107500Y1340500D03*
X110499Y1365050D03*
X109999Y1355050D03*
X138000Y1359025D03*
X111499Y1311800D03*
X125999Y1315550D03*
X132999Y1319550D03*
X142667Y1319218D03*
X149562Y1315987D03*
X133475Y1331200D03*
X112440Y1358196D03*
X112999Y1361550D03*
X97229Y1373337D03*
X97000Y1377600D03*
X109228Y1337090D03*
Y1333315D03*
X102700Y1321363D03*
X119499Y1339050D03*
X121000Y1364000D03*
X148024Y1333525D03*
X140000Y1332600D03*
X129000Y1356500D03*
X113500Y1344500D03*
Y1348154D03*
X102350Y1344500D03*
Y1348154D03*
X147400Y1321600D03*
X125100Y1366000D03*
X124290Y1469241D03*
X123808Y1465050D03*
X117390Y1426201D03*
Y1429976D03*
X104935Y1440634D03*
X142999Y1456373D03*
X104999Y1444941D03*
X106999Y1454450D03*
X100699Y1471050D03*
X139815Y1454438D03*
X139235Y1460973D03*
X123999Y1473050D03*
X127898Y1462441D03*
X107300Y1438100D03*
X114499Y1432050D03*
X114000Y1425400D03*
X107999Y1448050D03*
X150338Y1453958D03*
X152499Y1462940D03*
X105099Y1459150D03*
X142900Y1460000D03*
X100800Y1536450D03*
X98599Y1491350D03*
X157440Y1490460D03*
Y1500460D03*
Y1520460D03*
Y1530460D03*
X100499Y1479650D03*
X122199Y1476050D03*
X99899Y1539850D03*
X100000Y1546650D03*
X97499Y1554550D03*
X96999Y1558050D03*
X98144Y1534309D03*
X157400Y1596550D03*
X160200Y1598500D03*
X150999Y1713550D03*
X171999Y1662250D03*
X131999Y1710050D03*
X117499Y1706050D03*
X128749Y1703300D03*
X169100Y1685800D03*
X133090Y1699959D03*
X174250Y1694500D03*
X109499Y1712213D03*
X104999Y1708963D03*
X141500Y1715500D03*
X117249Y1712090D03*
X165575Y1676975D03*
X112753Y1716613D03*
X152633Y1677967D03*
X122642Y1704243D03*
X112562Y1720613D03*
X135499Y1710150D03*
X118499Y1694050D03*
X123749Y1711550D03*
X177900Y1690400D03*
X169600Y1682300D03*
X109499Y1743550D03*
X107300Y1746300D03*
X107100Y1736000D03*
X109399Y1739550D03*
X99199Y1761899D03*
X99999Y1753575D03*
X141999Y1764550D03*
X110099Y1759875D03*
X101399Y1784700D03*
X165900Y1790500D03*
X161900Y1793400D03*
X123393Y1870859D03*
X137999Y1861497D03*
Y1865151D03*
X123592Y1874254D03*
X96600Y1826000D03*
X135999Y1881550D03*
X141300Y1866400D03*
X141800Y1860500D03*
X97999Y1843050D03*
X159421Y1925972D03*
X210638Y62959D03*
X210634Y66863D03*
X201499Y104550D03*
X245499Y100550D03*
X246499Y86050D03*
Y80550D03*
X215138Y72559D03*
X210685Y74725D03*
X210605Y70692D03*
X205938Y72528D03*
X210738Y78459D03*
Y82159D03*
X186999Y99050D03*
X213499Y104650D03*
X223499Y108150D03*
X188999Y120800D03*
X205499Y105550D03*
X225499Y68550D03*
X233749Y110800D03*
X230749Y76300D03*
X207999Y109550D03*
X237899Y107050D03*
X197899Y165075D03*
X218499Y190550D03*
X247800Y269700D03*
X225298Y281114D03*
X213499Y283864D03*
X253871Y291410D03*
X250300Y275100D03*
X250400Y283100D03*
X239600Y278600D03*
X213400Y355300D03*
X224998Y357049D03*
X233998Y357549D03*
X239400Y357400D03*
X252935Y319114D03*
X214063Y318114D03*
X231800Y318414D03*
X179700Y425800D03*
X187699Y492850D03*
X199900Y554050D03*
X182499Y532550D03*
X220000Y516400D03*
X183499Y556100D03*
X188000Y484500D03*
X193549Y575875D03*
X246800Y677100D03*
X216999Y686550D03*
X213999Y725050D03*
X230849Y726050D03*
X252499D03*
X254499Y697700D03*
X249700Y682500D03*
X249800Y689900D03*
X238500Y680800D03*
X228999Y765550D03*
X218224Y765325D03*
X241600Y765700D03*
X236800Y765800D03*
X199000Y815000D03*
X200539Y890300D03*
X211750Y894600D03*
X198924Y975975D03*
X229562Y904113D03*
X215499Y905550D03*
X200799Y896600D03*
X233500Y1066100D03*
X226800Y1093400D03*
X221800Y1069300D03*
X247500Y1085500D03*
X256000Y1133000D03*
X255000Y1125700D03*
X221300Y1083238D03*
X251500Y1136700D03*
X229800Y1073600D03*
X242000Y1066000D03*
X182500Y1275500D03*
X199149Y1362900D03*
X194700Y1385700D03*
X181000Y1365500D03*
X180500Y1369900D03*
X229025Y1471576D03*
X241000Y1469600D03*
X224750Y1483950D03*
X232650Y1493450D03*
X233700Y1481600D03*
X199500Y1627000D03*
X195000Y1645500D03*
X179999Y1655887D03*
X186000Y1644000D03*
X179999Y1644500D03*
X181100Y1682700D03*
X194049Y1792600D03*
X201499Y1781050D03*
X227814Y1887513D03*
X231800Y1887100D03*
X236225Y1883125D03*
X229800Y1875700D03*
X218100Y1886400D03*
X213138Y1952703D03*
X249499Y1928050D03*
X231999Y1914050D03*
X210999Y1942050D03*
X223436Y1890465D03*
X232314Y1890513D03*
X213562Y1926113D03*
X220062Y1931113D03*
X240964Y1934113D03*
X214999Y1909550D03*
X257499Y1911050D03*
X249600Y1896800D03*
X343499Y60150D03*
X296099Y17100D03*
X305099Y17000D03*
X311400Y17100D03*
X317000Y17300D03*
X341499Y63050D03*
Y67110D03*
X343499Y31650D03*
X308999Y87050D03*
X323400Y105200D03*
X291999Y94050D03*
X282800Y87500D03*
X297499Y97550D03*
X315800Y100500D03*
X324800Y89400D03*
X293999Y293550D03*
X326499Y334054D03*
X284999Y338650D03*
X281499Y338550D03*
X313039Y352350D03*
X321900Y364600D03*
X298800Y333000D03*
X294500Y339000D03*
X326499Y337454D03*
X301249Y346050D03*
X344520Y406329D03*
X308999Y716450D03*
X315999Y718950D03*
X279939Y728610D03*
X329499Y801550D03*
X330540Y795509D03*
X327999Y740550D03*
X320499Y798050D03*
X285499Y745050D03*
X282099D03*
X292999Y743650D03*
X298000Y743500D03*
X323249Y749010D03*
X324959Y766750D03*
X277039Y740300D03*
X327749Y744050D03*
X306500Y753550D03*
X340699Y1046086D03*
X269500Y1135500D03*
X282500Y1135000D03*
X283499Y1556050D03*
X279999D03*
X289999Y1554650D03*
X293700Y1553351D03*
X276039Y1551300D03*
X314999Y1527550D03*
X326500Y1550200D03*
X261999Y1516050D03*
X295000Y1513000D03*
X333000Y1578000D03*
X297800Y1561600D03*
X291400Y1561500D03*
X324000Y1562500D03*
X312999Y1566050D03*
X323999Y1577250D03*
X330300Y1561200D03*
X310249Y1569800D03*
X264499Y1964050D03*
X331622Y1944767D03*
X288709Y1948042D03*
X284999Y1947691D03*
X342999Y1947409D03*
X342621Y1943409D03*
X330500Y1966500D03*
X280689Y1942710D03*
X315999Y1958550D03*
X327100Y1966472D03*
X329999Y1952273D03*
X325221Y1927272D03*
X313499Y1919050D03*
X332103Y1948133D03*
X310499Y1957050D03*
X285499Y1930050D03*
X381999Y57050D03*
X398799Y36152D03*
X381999Y50150D03*
X386799Y45000D03*
X381999Y53550D03*
X394199Y45050D03*
X358999Y61550D03*
X354999Y72050D03*
X426000Y93500D03*
X357503Y77043D03*
X374499Y77550D03*
X385999Y78050D03*
X401499Y80550D03*
X371700Y85500D03*
X400499Y406329D03*
X371999Y549300D03*
X394649Y630600D03*
X350499Y597300D03*
X375999Y698550D03*
X350499Y715050D03*
X371500Y880600D03*
X364499Y1099050D03*
X372999Y1123550D03*
X345499Y1096550D03*
X370149Y1320050D03*
X345424Y1310050D03*
X347324Y1524000D03*
X366149Y1554050D03*
X402499Y1476850D03*
X390999Y1514398D03*
Y1517798D03*
X349774Y1582900D03*
X354500Y1559500D03*
X400999Y1575550D03*
X354000Y1584900D03*
X353499Y1710450D03*
X377900Y1703800D03*
X348499Y1762050D03*
X385499Y1735050D03*
X367000Y1810000D03*
X360000Y1967500D03*
X645549Y1815134D03*
X644360Y1819137D03*
X659549Y1810634D03*
X757499Y745342D03*
Y1079550D03*
X755600Y1149800D03*
X758499Y1371050D03*
X757999Y1484050D03*
X754000Y1551000D03*
X750000Y1560500D03*
X732549Y1806634D03*
X733149Y1798634D03*
X690249Y1805634D03*
X707600Y1815600D03*
X733049Y1814134D03*
X755000Y1825000D03*
X711652Y1822109D03*
X711848Y1825504D03*
X758499Y1893550D03*
X752500Y1954500D03*
X821999Y193116D03*
X827499Y163550D03*
X820749Y163850D03*
X813249Y163800D03*
X839249Y164050D03*
X829917Y216200D03*
X833576Y215432D03*
X837999Y219550D03*
X822100Y279500D03*
X827500Y274500D03*
X770999Y302050D03*
X785499Y291050D03*
X770999Y290050D03*
Y295550D03*
X827499Y313424D03*
X763571Y295622D03*
X777999Y296050D03*
X786978Y298529D03*
X836500Y274950D03*
X812500Y282750D03*
X809940Y264940D03*
X822100Y261700D03*
X816700Y274300D03*
X791499Y333050D03*
X789999Y336550D03*
X772499Y323050D03*
X758778Y345000D03*
X768178Y333964D03*
X784499Y334050D03*
X772873Y326924D03*
X780499Y330050D03*
X771105Y722789D03*
X829800Y666650D03*
X835150Y677650D03*
X806500Y687250D03*
X781999Y725550D03*
X808660Y667540D03*
X820600Y664300D03*
X813200Y675900D03*
X788999Y736050D03*
X791999Y733050D03*
X766499Y732842D03*
X762500Y734000D03*
X784939Y733550D03*
X769999Y733050D03*
X792154Y1135926D03*
X825700Y1083100D03*
X771999Y1124550D03*
X767083Y1134550D03*
X764549Y1138500D03*
X784439Y1136550D03*
X814000Y1087000D03*
X772499Y1130050D03*
X789499Y1138050D03*
X779499Y1131050D03*
X807000Y1072900D03*
X825800Y1072300D03*
X815400Y1078800D03*
X803199Y1151850D03*
X822100Y1466800D03*
X774542Y1530050D03*
X804899Y1556950D03*
X827700Y1487600D03*
X836625Y1487400D03*
X771225Y1539474D03*
X767936Y1540336D03*
X784577Y1535628D03*
X812550Y1494050D03*
X774577Y1533796D03*
X791499Y1543550D03*
X793999Y1541050D03*
X784499Y1529050D03*
X809960Y1478040D03*
X814700Y1486300D03*
X788000Y1788000D03*
X774500D03*
X812000Y1799500D03*
X821249Y1791250D03*
X811000Y1793000D03*
X793000Y1803500D03*
X795849Y1805500D03*
X828500Y1877800D03*
X770999Y1820550D03*
X822499Y1815164D03*
X791999Y1819050D03*
X783499Y1827050D03*
X807000Y1822300D03*
X803500Y1822708D03*
X810900Y1882440D03*
X822700Y1871100D03*
X805900Y1887560D03*
X771499Y1936550D03*
X802499Y1951550D03*
X800431Y1941193D03*
X767999Y1945173D03*
X764908Y1946592D03*
X785939Y1946800D03*
X812500Y1898500D03*
X771499Y1940050D03*
X802099Y1961950D03*
X834799Y1946950D03*
X792499Y1949050D03*
X794499Y1941050D03*
X782999Y1937050D03*
X919800Y54600D03*
X924200Y69800D03*
X898800Y96000D03*
X855500Y149500D03*
X873000Y148500D03*
X846500Y149500D03*
X841499Y135550D03*
X861999Y146550D03*
X882499Y147050D03*
X896999Y141550D03*
X916499Y115050D03*
X923761Y85550D03*
X907499Y131800D03*
X902499Y110550D03*
X901499Y92050D03*
X898999Y110550D03*
X897555Y90494D03*
X910999Y124550D03*
X916499Y172550D03*
X867500Y163924D03*
X867576Y159924D03*
X878078Y240103D03*
Y243878D03*
X854400Y264600D03*
X847878Y250040D03*
X851278Y249974D03*
X842499Y280924D03*
X847500Y246600D03*
X850999Y246550D03*
X874700Y244900D03*
X874900Y238600D03*
X871999Y283924D03*
X886200Y313924D03*
X886600Y303924D03*
X872136Y273924D03*
X858478Y274050D03*
X868799Y294750D03*
X865499Y288050D03*
X867899Y321550D03*
X868299Y336150D03*
X902999Y556050D03*
X878596Y645573D03*
X875100Y644400D03*
X922049Y574375D03*
X879750Y570550D03*
X879950Y565050D03*
X851172Y655432D03*
X878596Y649348D03*
X847772Y655370D03*
X875300Y650500D03*
X851300Y651700D03*
X847600Y651600D03*
X852696Y671197D03*
X922049Y978575D03*
X900499Y962100D03*
X879708Y971892D03*
X878233Y1051095D03*
X877964Y1054485D03*
X850833Y1061441D03*
X847233Y1061492D03*
X847500Y1057800D03*
X851000Y1058000D03*
X874733Y1055792D03*
X874999Y1049550D03*
X900999Y979050D03*
X883083Y979183D03*
X864499Y1128750D03*
X852333Y1077716D03*
X871499Y1124948D03*
X872086Y1114948D03*
X871999Y1094948D03*
X872086Y1084948D03*
X860133Y1084142D03*
X860799Y1358925D03*
X861849Y1376050D03*
X866700Y1379796D03*
X866596Y1375796D03*
X848888Y1466402D03*
X852288Y1466346D03*
X878054Y1456450D03*
X877853Y1459991D03*
X874100Y1461600D03*
X874900Y1454000D03*
X848861Y1462463D03*
X852500Y1462600D03*
X867523Y1542821D03*
X867199Y1535150D03*
X854327Y1477550D03*
X858827Y1485696D03*
X872086Y1490460D03*
X871999Y1500460D03*
Y1520460D03*
X872086Y1530460D03*
X863699Y1501250D03*
X900500Y1721500D03*
X886439Y1717600D03*
X862800Y1712700D03*
X889800Y1711500D03*
X921549Y1788475D03*
X917499Y1796550D03*
X879700Y1786300D03*
X873300Y1740100D03*
X879664Y1782213D03*
X866914Y1861840D03*
X853499Y1871036D03*
X866914Y1865615D03*
X850099Y1871056D03*
X851500Y1821400D03*
X849375Y1824982D03*
X854905Y1825583D03*
X854480Y1867578D03*
X849999Y1867550D03*
X863700Y1867300D03*
X865300Y1858700D03*
X854814Y1883550D03*
X859314Y1891365D03*
X871921Y1905972D03*
X871421Y1895972D03*
X872086Y1925972D03*
Y1935972D03*
X863699Y1906450D03*
X857099Y1917650D03*
X961499Y100050D03*
X946899Y122550D03*
X932961Y85581D03*
X928461Y75981D03*
X928561Y91481D03*
X928508Y87747D03*
X928428Y83714D03*
X928561Y95181D03*
X928457Y79885D03*
X958999Y96050D03*
X930999Y115550D03*
X937999Y122050D03*
X938499Y115550D03*
X961499Y93350D03*
X926999Y122050D03*
X943499Y82550D03*
X934499Y118750D03*
X926999Y115050D03*
X939549Y175175D03*
X966499Y552050D03*
X965999Y954550D03*
X986400Y1639302D03*
X987100Y1624900D03*
X981200Y1625800D03*
X990425Y1633898D03*
X987029Y1634075D03*
X981200Y1618002D03*
X964000Y1639200D03*
X960900Y1636400D03*
X969600Y1638300D03*
X977500Y1660500D03*
X978000Y1668000D03*
X967600Y1651100D03*
X989502Y1646000D03*
X988800Y1658300D03*
X989000Y1663802D03*
X987200Y1675600D03*
X989900Y1678800D03*
X974000Y1670700D03*
X984211Y1667500D03*
X971558Y1646500D03*
X981500Y1653000D03*
X980800Y1659600D03*
X982050Y1649302D03*
X1281550Y1899850D03*
G54D14*
X17720Y1903144D03*
X29532Y309561D03*
Y1029522D03*
X271657Y267711D03*
Y673223D03*
Y1078734D03*
Y1484246D03*
Y1889758D03*
X994098Y149601D03*
Y673223D03*
X994099Y1068892D03*
X1281550Y1843650D03*
G54D15*
X68898Y17047D03*
Y190275D03*
Y422559D03*
Y595787D03*
Y828071D03*
Y1001299D03*
Y1233583D03*
Y1406811D03*
Y1639095D03*
Y1812323D03*
X167323Y179803D03*
Y353031D03*
Y585315D03*
Y758543D03*
Y990827D03*
Y1164055D03*
Y1396339D03*
Y1569567D03*
Y1801851D03*
Y1975079D03*
X895669Y179803D03*
Y353031D03*
Y585315D03*
Y758543D03*
Y990827D03*
Y1164055D03*
Y1396339D03*
Y1569567D03*
Y1801851D03*
Y1975079D03*
X1281550Y1675050D03*
G54D16*
X78150Y28858D03*
Y178464D03*
Y434370D03*
Y583976D03*
Y839882D03*
Y989488D03*
Y1245394D03*
Y1395000D03*
Y1650906D03*
Y1800512D03*
X158071Y191614D03*
Y341220D03*
Y597126D03*
Y746732D03*
Y1002638D03*
Y1152244D03*
Y1408150D03*
Y1557756D03*
Y1813662D03*
Y1963268D03*
X886417Y191614D03*
Y341220D03*
Y597126D03*
Y746732D03*
Y1002638D03*
Y1152244D03*
Y1408150D03*
Y1557756D03*
Y1813662D03*
Y1963268D03*
X1281550Y1787450D03*
G54D17*
X129920Y17716D03*
X994093Y1889751D03*
X1281550Y1815550D03*
G54D18*
X1019291Y1416024D03*
Y1694212D03*
X1281550Y1703150D03*
G54D19*
G01X-71137Y-139897D02*
Y-219897D01*
G01D02*
X1129963D01*
G01X-75137Y-123897D02*
G02I-12000J0D01*
G01X-80287D02*
G02I-6850J0D01*
G01X-87137Y-139897D02*
Y-107897D01*
G01X-71137Y-123897D02*
X-103137D01*
G01X-71137Y-139897D02*
X1129963D01*
G01X-71137Y-175397D02*
X1129963D01*
G01X342463Y-139897D02*
Y-219897D01*
G01X479963Y-139897D02*
Y-219897D01*
G01X594963Y-139897D02*
Y-219897D01*
G01X762463Y-139897D02*
Y-219897D01*
G01X932463Y-139897D02*
Y-219897D01*
G01X1129963Y-139897D02*
Y-219897D01*
G01X1157963Y-123897D02*
G02I-12000J0D01*
G01X1152813D02*
G02I-6850J0D01*
G01X1145963Y-139897D02*
Y-107897D01*
G01X1161963Y-123897D02*
X1129963D01*
M02*
